# Altium SchDoc records: MAC.SchDoc
|HEADER=Protel for Windows - Schematic Capture Binary File Version 5.0|Weight=979|MinorVersion=4
|RECORD=31|FontIdCount=8|Size1=10|FontName1=Times New Roman|Size2=8|FontName2=Arial|Size3=10|FontName3=Arial|Size4=12|Underline4=T|FontName4=Arial|Size5=11|FontName5=Arial|Size6=24|FontName6=Times New Roman|Size7=10|Underline7=T|FontName7=Times New Roman|Size8=12|FontName8=Arial|UseMBCS=T|IsBOC=T|HotSpotGridOn=T|HotSpotGridSize_Frac=50000|SheetStyle=12|SystemFont=3|BorderOn=T|SheetNumberSpaceSize=12|AreaColor=16317695|SnapGridOn=T|SnapGridSize=10|VisibleGridOn=T|VisibleGridSize=10|CustomX=2338|CustomX_Frac=58268|CustomY=1653|CustomY_Frac=54331|CustomXZones=8|CustomYZones=6|CustomMarginWidth=19|CustomMarginWidth_Frac=80000|ShowTemplateGraphics=T|TemplateFileName=C:\Users\<user>\Documents\Altium\AD20\Templates\Timecard.SchDot|Display_Unit=0
|RECORD=39|IsNotAccesible=T|OwnerPartId=-1|FileName=C:\Users\<user>\Documents\Altium\AD20\Templates\Timecard.SchDot
|RECORD=4|OwnerIndex=1|OwnerPartId=-1|Location.X=1594|Location.Y=39|Color=8388608|FontID=4|Text=timingcard.com|URL=http://timingcard.com
|RECORD=6|OwnerIndex=1|IndexInSheet=1|OwnerPartId=-1|LocationCount=2|X1=1680|Y1=35|X2=1576|Y2=35
|RECORD=4|OwnerIndex=1|IndexInSheet=2|OwnerPartId=-1|Location.X=1615|Location.Y=27|Justification=4|Color=16711680|FontID=5|Text==SheetNumber
|RECORD=4|OwnerIndex=1|IndexInSheet=3|OwnerPartId=-1|Location.X=1581|Location.X_Frac=42446|Location.Y=29|Location.Y_Frac=96838|Justification=3|FontID=2|Text=SHEET
|RECORD=4|OwnerIndex=1|IndexInSheet=4|OwnerPartId=-1|Location.X=1639|Location.X_Frac=42446|Location.Y=29|Location.Y_Frac=96838|Justification=3|FontID=2|Text=OF
|RECORD=6|OwnerIndex=1|IndexInSheet=5|OwnerPartId=-1|LineWidth=1|LocationCount=2|X1=1679|X1_Frac=42446|Y1=117|Y1_Frac=96838|X2=1576|Y2=118
|RECORD=4|OwnerIndex=1|IndexInSheet=6|OwnerPartId=-1|Location.X=1659|Location.Y=27|Justification=4|Color=16711680|FontID=5|Text==SheetTotal
|RECORD=30|OwnerIndex=1|IndexInSheet=7|OwnerPartId=-1|Location.X=1578|Location.Y=65|Corner.X=1673|Corner.X_Frac=88801|Corner.Y=115|KeepAspect=T|FileName=C:\Users\<user>\Desktop\Timecard Logo\TIMECARD.jpg
|RECORD=6|OwnerIndex=1|IndexInSheet=8|OwnerPartId=-1|LineWidth=1|LocationCount=2|X1=1576|X1_Frac=3162|Y1=117|Y1_Frac=42446|X2=1576|Y2=21
|RECORD=6|OwnerIndex=1|IndexInSheet=9|OwnerPartId=-1|LocationCount=2|X1=1680|Y1=51|X2=1576|Y2=51
|RECORD=4|OwnerIndex=1|IndexInSheet=10|OwnerPartId=-1|Location.X=1581|Location.X_Frac=42446|Location.Y=56|Location.Y_Frac=96838|Justification=3|FontID=2|Text=REV
|RECORD=4|OwnerIndex=1|IndexInSheet=11|OwnerPartId=-1|Location.X=1619|Location.Y=57|Justification=3|FontID=2|Text=DATE
|RECORD=6|OwnerIndex=1|IndexInSheet=12|OwnerPartId=-1|LocationCount=2|X1=1680|Y1=65|X2=1576|Y2=65
|RECORD=4|OwnerIndex=1|IndexInSheet=13|OwnerPartId=-1|Location.X=1605|Location.Y=58|Justification=4|Color=16711680|FontID=5|Text==ProjectRevision
|RECORD=4|OwnerIndex=1|IndexInSheet=14|OwnerPartId=-1|Location.X=1659|Location.Y=58|Justification=4|Color=16711680|FontID=5|Text==ProjectDate
|RECORD=41|IndexInSheet=1|OwnerPartId=-1|Location.X=21474|Location.X_Frac=83647|Location.Y=21464|Location.Y_Frac=83647|Color=8388608|FontID=1|IsHidden=T|Text=01910|Name=Customer
|RECORD=41|IndexInSheet=2|OwnerPartId=-1|Location.X=1000|Location.Y=10|Color=8388608|FontID=1|IsHidden=T|Text=*|Name=DocStatus
|RECORD=17|IndexInSheet=3|OwnerPartId=-1|ShowNetName=T|Location.X=1018|Location.Y=987|Color=255|FontID=1|Text=MAC_TX|IsCrossSheetConnector=T
|RECORD=17|IndexInSheet=4|OwnerPartId=-1|ShowNetName=T|Location.X=1018|Location.Y=977|Color=255|FontID=1|Text=MAC_RX|IsCrossSheetConnector=T
|RECORD=17|IndexInSheet=5|OwnerPartId=-1|ShowNetName=T|Location.X=1018|Location.Y=967|Color=255|FontID=1|Text=MAC_BITE|IsCrossSheetConnector=T
|RECORD=17|IndexInSheet=6|OwnerPartId=-1|ShowNetName=T|Location.X=718|Location.Y=967|Orientation=2|Color=255|FontID=1|Text=MAC_RF_OUT|IsCrossSheetConnector=T
|RECORD=17|IndexInSheet=7|OwnerPartId=-1|ShowNetName=T|Location.X=718|Location.Y=987|Orientation=2|Color=255|FontID=1|Text=MAC_FREQ_CTRL|IsCrossSheetConnector=T
|RECORD=22|IndexInSheet=8|OwnerPartId=-1|Location.X=780|Location.Y=800|Color=255|Orientation=1|Symbol=Thin Cross|IsActive=T|SuppressAll=T
|RECORD=22|IndexInSheet=9|OwnerPartId=-1|Location.X=780|Location.Y=790|Color=255|Orientation=1|Symbol=Thin Cross|IsActive=T|SuppressAll=T
|RECORD=22|IndexInSheet=10|OwnerPartId=-1|Location.X=780|Location.Y=780|Color=255|Orientation=1|Symbol=Thin Cross|IsActive=T|SuppressAll=T
|RECORD=22|IndexInSheet=11|OwnerPartId=-1|Location.X=780|Location.Y=770|Color=255|Orientation=1|Symbol=Thin Cross|IsActive=T|SuppressAll=T
|RECORD=22|IndexInSheet=12|OwnerPartId=-1|Location.X=780|Location.Y=760|Color=255|Orientation=1|Symbol=Thin Cross|IsActive=T|SuppressAll=T
|RECORD=22|IndexInSheet=13|OwnerPartId=-1|Location.X=780|Location.Y=750|Color=255|Orientation=1|Symbol=Thin Cross|IsActive=T|SuppressAll=T
|RECORD=22|IndexInSheet=14|OwnerPartId=-1|Location.X=780|Location.Y=740|Color=255|Orientation=1|Symbol=Thin Cross|IsActive=T|SuppressAll=T
|RECORD=17|IndexInSheet=15|OwnerPartId=-1|ShowNetName=T|Location.X=970|Location.Y=260|Orientation=2|Color=255|FontID=1|Text=FPGA_MAC_PPS_IN0-|IsCrossSheetConnector=T
|RECORD=17|IndexInSheet=16|OwnerPartId=-1|ShowNetName=T|Location.X=1210|Location.Y=850|Color=255|FontID=1|Text=MAC_USB+|IsCrossSheetConnector=T
|RECORD=17|IndexInSheet=17|OwnerPartId=-1|ShowNetName=T|Location.X=1210|Location.Y=840|Color=255|FontID=1|Text=MAC_USB-|IsCrossSheetConnector=T
|RECORD=17|IndexInSheet=18|OwnerPartId=-1|ShowNetName=T|Location.X=1210|Location.Y=830|Color=255|FontID=1|Text=MAC_USB_PWR|IsCrossSheetConnector=T
|RECORD=17|IndexInSheet=19|OwnerPartId=-1|ShowNetName=T|Location.X=190|Location.Y=310|Orientation=2|Color=255|FontID=1|Text=MAC_PPS_OUT+|IsCrossSheetConnector=T
|RECORD=17|IndexInSheet=20|OwnerPartId=-1|ShowNetName=T|Location.X=190|Location.Y=250|Orientation=2|Color=255|FontID=1|Text=MAC_PPS_OUT-|IsCrossSheetConnector=T
|RECORD=17|IndexInSheet=21|OwnerPartId=-1|ShowNetName=T|Location.X=1210|Location.Y=780|Color=255|FontID=1|Text=MAC_ALARM|IsCrossSheetConnector=T
|RECORD=17|IndexInSheet=22|OwnerPartId=-1|Style=4|ShowNetName=T|Location.X=980|Location.Y=720|Orientation=3|Color=128|FontID=1|Text=GND
|RECORD=17|IndexInSheet=23|OwnerPartId=-1|Style=4|ShowNetName=T|Location.X=748|Location.Y=937|Orientation=3|Color=128|FontID=1|Text=GND
|RECORD=17|IndexInSheet=24|OwnerPartId=-1|Style=4|ShowNetName=T|Location.X=1340|Location.Y=906|Orientation=3|Color=128|FontID=1|Text=GND
|RECORD=4|IndexInSheet=25|OwnerPartId=-1|Location.X=848|Location.Y=1037|Color=8388608|FontID=6|Text=MAC
|RECORD=1|LibReference=CAP_0805_10UF_25V|ComponentDescription=CAP, CER, 10.UF, 25V, 10%, X5R, 0805|PartCount=2|DisplayModeCount=1|IndexInSheet=26|OwnerPartId=-1|Location.X=1261|Location.Y=896|CurrentPartId=1|LibraryPath=*|SourceLibraryName=Capacitors.IntLib|TargetFileName=*|AreaColor=11599871|Color=128|PartIDLocked=F|DesignItemId=CAP_0805_10UF_25V|AllPinCount=2
|RECORD=41|OwnerIndex=42|OwnerPartId=-1|Location.X=1261|Location.Y=896|Color=8388608|FontID=8|IsHidden=T|Text=TAIYO YUDEN|Name=MFG NAME
|RECORD=41|OwnerIndex=42|IndexInSheet=1|OwnerPartId=-1|Location.X=1261|Location.Y=896|Color=8388608|FontID=8|IsHidden=T|Text=TMK212BBJ106KG-T|Name=MFG PART NUM
|RECORD=41|OwnerIndex=42|IndexInSheet=2|OwnerPartId=-1|Location.X=1261|Location.Y=896|Color=8388608|FontID=8|IsHidden=T|Text=10/23/2013|Name=MODIFY DATE
|RECORD=41|OwnerIndex=42|IndexInSheet=3|OwnerPartId=-1|Location.X=1261|Location.Y=896|Color=8388608|FontID=8|IsHidden=T|Text=CAP, CER|Name=CATEGORY
|RECORD=41|OwnerIndex=42|IndexInSheet=4|OwnerPartId=-1|Location.X=1259|Location.Y=908|Location.Y_Frac=50000|Color=8388608|FontID=8|IsHidden=T|Text=4/11/2006 3:37:28 PM|Name=Date
|RECORD=41|OwnerIndex=42|IndexInSheet=5|OwnerPartId=-1|Location.X=1267|Location.Y=970|Location.Y_Frac=48252|Color=8388608|FontID=8|IsHidden=T|Text=*|Name=SHEETPART
|RECORD=41|OwnerIndex=42|IndexInSheet=6|OwnerPartId=-1|Location.X=1267|Location.Y=970|Location.Y_Frac=48252|Color=8388608|FontID=8|IsHidden=T|Text=10%|Name=P1
|RECORD=41|OwnerIndex=42|IndexInSheet=7|OwnerPartId=-1|Location.X=1267|Location.Y=970|Location.Y_Frac=48252|Color=8388608|FontID=8|IsHidden=T|Text=85C|Name=MAXTEMP
|RECORD=41|OwnerIndex=42|IndexInSheet=8|OwnerPartId=-1|Location.X=1267|Location.Y=970|Location.Y_Frac=48252|Color=8388608|FontID=8|IsHidden=T|Text=-55C|Name=MINTEMP
|RECORD=41|OwnerIndex=42|IndexInSheet=9|OwnerPartId=-1|Location.X=1267|Location.Y=970|Location.Y_Frac=48252|Color=8388608|FontID=8|IsHidden=T|Name=OTHER
|RECORD=41|OwnerIndex=42|IndexInSheet=10|OwnerPartId=-1|Location.X=1267|Location.Y=970|Location.Y_Frac=48252|Color=8388608|FontID=8|IsHidden=T|Text=25V|Name=P2
|RECORD=41|OwnerIndex=42|IndexInSheet=11|OwnerPartId=-1|Location.X=1267|Location.Y=970|Location.Y_Frac=48252|Color=8388608|FontID=8|IsHidden=T|Text=X5R|Name=P3
|RECORD=41|OwnerIndex=42|IndexInSheet=12|OwnerPartId=-1|Location.X=1267|Location.Y=970|Location.Y_Frac=48252|Color=8388608|FontID=8|IsHidden=T|Text=0805|Name=Size
|RECORD=41|OwnerIndex=42|IndexInSheet=13|OwnerPartId=-1|Location.X=1267|Location.Y=970|Location.Y_Frac=48252|Color=8388608|FontID=8|IsHidden=T|Name=SUB
|RECORD=41|OwnerIndex=42|IndexInSheet=14|OwnerPartId=-1|Location.X=1267|Location.Y=970|Location.Y_Frac=48252|Color=8388608|FontID=1|IsHidden=T|Text=CAP, CER, 10.UF, 10V, 10%, X5R, 0805|Name=DESC
|RECORD=41|OwnerIndex=42|IndexInSheet=15|OwnerPartId=-1|Location.X=1267|Location.Y=969|Location.Y_Frac=98252|Color=8388608|FontID=1|IsHidden=T|Text=MOUSER|Name=Supplier 1|ReadOnlyState=1
|RECORD=41|OwnerIndex=42|IndexInSheet=16|OwnerPartId=-1|Location.X=1267|Location.Y=969|Location.Y_Frac=98252|Color=8388608|FontID=1|IsHidden=T|Text=963-TMK212BBJ106KG-T|Name=Supplier Part Number 1|ReadOnlyState=1
|RECORD=41|OwnerIndex=42|IndexInSheet=17|OwnerPartId=-1|Location.X=1291|Location.Y=926|Color=8388608|FontID=8|Text=10uF|Name=VALUE
|RECORD=2|OwnerIndex=42|OwnerPartId=1|FormalType=1|Electrical=4|PinConglomerate=35|PinLength=10|Location.X=1281|Location.Y=926|Name=2|Designator=2|SwapIdPin=2|SwapIDPart=1|PinPropagationDelay=0.000000E+000
|RECORD=2|OwnerIndex=42|OwnerPartId=1|FormalType=1|Electrical=4|PinConglomerate=33|PinLength=10|Location.X=1281|Location.Y=936|Name=1|Designator=1|SwapIdPin=1|SwapIDPart=1|PinPropagationDelay=0.000000E+000
|RECORD=13|OwnerIndex=42|IsNotAccesible=T|IndexInSheet=20|OwnerPartId=1|Location.X=1281|Location.Y=928|Location.Y_Frac=50000|Corner.X=1281|Corner.Y=926|LineWidth=1|Color=16711680
|RECORD=13|OwnerIndex=42|IsNotAccesible=T|IndexInSheet=21|OwnerPartId=1|Location.X=1281|Location.Y=936|Corner.X=1281|Corner.Y=933|Corner.Y_Frac=50000|LineWidth=1|Color=16711680
|RECORD=13|OwnerIndex=42|IsNotAccesible=T|IndexInSheet=22|OwnerPartId=1|Location.X=1286|Location.Y=928|Location.Y_Frac=50000|Corner.X=1276|Corner.Y=928|Corner.Y_Frac=50000|LineWidth=1|Color=16711680
|RECORD=13|OwnerIndex=42|IsNotAccesible=T|IndexInSheet=23|OwnerPartId=1|Location.X=1286|Location.Y=933|Location.Y_Frac=50000|Corner.X=1276|Corner.Y=933|Corner.Y_Frac=50000|LineWidth=1|Color=16711680
|RECORD=41|OwnerIndex=42|IndexInSheet=24|OwnerPartId=-1|Location.X=1267|Location.Y=969|Location.Y_Frac=98951|Color=8388608|FontID=1|IsHidden=T|Text=<VALENTIUM>|Name=VALENTIUM PART NUM
|RECORD=34|OwnerIndex=42|IndexInSheet=-1|OwnerPartId=-1|Location.X=1291|Location.Y=936|Color=8388608|FontID=1|Text=C62|Name=Designator|ReadOnlyState=1
|RECORD=41|OwnerIndex=42|IndexInSheet=-1|OwnerPartId=-1|Location.X=1288|Location.X_Frac=50000|Location.Y=891|Color=8388608|FontID=1|IsHidden=T|Text=CAP_0805_10UF_25V|Name=Comment
|RECORD=44|OwnerIndex=42
|RECORD=45|OwnerIndex=72|IndexInSheet=-1|Description=Chip Capacitor, 0805, 2-Leads, Body 2.00x1.25mm, IPC Medium Density|UseComponentLibrary=T|ModelName=CAPC2012X14N|ModelType=PCBLIB|DatafileCount=1|ModelDatafileEntity0=CAPC2012X14N|ModelDatafileKind0=PCBLib|IsCurrent=T|DatalinksLocked=T|DatabaseDatalinksLocked=T|IntegratedModel=T|DatabaseModel=T
|RECORD=46|OwnerIndex=73
|RECORD=48|OwnerIndex=73
|RECORD=1|LibReference=MAC-SA5X|ComponentDescription=MOD, MAC, MAC-SA5X, ATOMIC CLOCK|PartCount=3|DisplayModeCount=1|IndexInSheet=27|OwnerPartId=-1|Location.X=868|Location.Y=977|CurrentPartId=1|LibraryPath=*|SourceLibraryName=Modules.IntLib|TargetFileName=*|AreaColor=11599871|Color=128|PartIDLocked=F|DesignItemId=MAC-SA5X|AllPinCount=28
|RECORD=41|OwnerIndex=76|OwnerPartId=-1|Location.X=766|Location.Y=997|Color=8388608|FontID=8|IsHidden=T|Text=3/22/2006 1:36:44 PM|Name=MODIFY DATE
|RECORD=41|OwnerIndex=76|IndexInSheet=1|OwnerPartId=-1|Location.X=766|Location.Y=997|Color=8388608|FontID=8|IsHidden=T|Text=MAC-SA5X|Name=MFG PART NUM
|RECORD=41|OwnerIndex=76|IndexInSheet=2|OwnerPartId=-1|Location.X=766|Location.Y=997|Color=8388608|FontID=8|IsHidden=T|Text=MOD|Name=CATEGORY
|RECORD=41|OwnerIndex=76|IndexInSheet=3|OwnerPartId=-1|Location.X=766|Location.Y=997|Color=8388608|FontID=8|IsHidden=T|Name=DATE
|RECORD=41|OwnerIndex=76|IndexInSheet=4|OwnerPartId=-1|Location.X=766|Location.Y=997|Color=8388608|FontID=8|IsHidden=T|Text=MICROCHIP|Name=MFG NAME
|RECORD=41|OwnerIndex=76|IndexInSheet=5|OwnerPartId=-1|Location.X=766|Location.Y=997|Color=8388608|FontID=8|IsHidden=T|Text=85C|Name=MAXTEMP
|RECORD=41|OwnerIndex=76|IndexInSheet=6|OwnerPartId=-1|Location.X=766|Location.Y=997|Color=8388608|FontID=8|IsHidden=T|Text=-40C|Name=MINTEMP
|RECORD=41|OwnerIndex=76|IndexInSheet=7|OwnerPartId=-1|Location.X=766|Location.Y=997|Color=8388608|FontID=8|IsHidden=T|Text=AEC-Q200|Name=OTHER
|RECORD=41|OwnerIndex=76|IndexInSheet=8|OwnerPartId=-1|Location.X=766|Location.Y=997|Color=8388608|FontID=8|IsHidden=T|Text=ATOMIC CLOCK|Name=P1
|RECORD=41|OwnerIndex=76|IndexInSheet=9|OwnerPartId=-1|Location.X=766|Location.Y=997|Color=8388608|FontID=8|IsHidden=T|Name=P2
|RECORD=41|OwnerIndex=76|IndexInSheet=10|OwnerPartId=-1|Location.X=766|Location.Y=997|Color=8388608|FontID=8|IsHidden=T|Name=P3
|RECORD=41|OwnerIndex=76|IndexInSheet=11|OwnerPartId=-1|Location.X=766|Location.Y=997|Color=8388608|FontID=8|IsHidden=T|Name=SIZE
|RECORD=41|OwnerIndex=76|IndexInSheet=12|OwnerPartId=-1|Location.X=766|Location.Y=997|Color=8388608|FontID=8|IsHidden=T|Name=SUB
|RECORD=41|OwnerIndex=76|IndexInSheet=13|OwnerPartId=-1|Location.X=766|Location.Y=997|Color=8388608|FontID=1|IsHidden=T|Text=*|Name=SHEETPART
|RECORD=41|OwnerIndex=76|IndexInSheet=14|OwnerPartId=-1|Location.X=766|Location.Y=997|Color=8388608|FontID=1|IsHidden=T|Text=MOD, MAC, MAC-SA5X, ATOMIC CLOCK|Name=DESC
|RECORD=41|OwnerIndex=76|IndexInSheet=15|OwnerPartId=-1|Location.X=766|Location.Y=997|Color=8388608|FontID=1|IsHidden=T|Text=<V PART NUM>|Name=VELENTIUM PART NUM
|RECORD=14|OwnerIndex=76|IsNotAccesible=T|IndexInSheet=16|OwnerPartId=1|Location.X=798|Location.Y=947|Corner.X=948|Corner.Y=997|Color=128|AreaColor=11599871|IsSolid=T
|RECORD=2|OwnerIndex=76|OwnerPartId=1|FormalType=1|Electrical=4|PinConglomerate=58|PinLength=30|Location.X=798|Location.Y=987|Name=FREQ CTRL IN|Designator=P1|PinPropagationDelay=0.000000E+000
|RECORD=2|OwnerIndex=76|OwnerPartId=1|FormalType=1|Electrical=4|PinConglomerate=58|PinLength=30|Location.X=798|Location.Y=977|Name=GND (CASE)|Designator=P2|PinPropagationDelay=0.000000E+000
|RECORD=2|OwnerIndex=76|OwnerPartId=1|FormalType=1|Electrical=4|PinConglomerate=58|PinLength=30|Location.X=798|Location.Y=967|Name=RF OUT|Designator=P3|PinPropagationDelay=0.000000E+000
|RECORD=2|OwnerIndex=76|OwnerPartId=1|FormalType=1|Electrical=4|PinConglomerate=58|PinLength=30|Location.X=798|Location.Y=957|Name=GND (SUPPLY & SIGNAL)|Designator=P4|PinPropagationDelay=0.000000E+000
|RECORD=2|OwnerIndex=76|OwnerPartId=1|FormalType=1|Electrical=4|PinConglomerate=56|PinLength=30|Location.X=948|Location.Y=957|Name=VCC|Designator=P5|PinPropagationDelay=0.000000E+000
|RECORD=2|OwnerIndex=76|OwnerPartId=1|FormalType=1|Electrical=4|PinConglomerate=56|PinLength=30|Location.X=948|Location.Y=967|Name=BITE|Designator=P6|PinPropagationDelay=0.000000E+000
|RECORD=2|OwnerIndex=76|OwnerPartId=1|FormalType=1|Electrical=4|PinConglomerate=56|PinLength=30|Location.X=948|Location.Y=977|Name=RS-232 TX|Designator=P7|PinPropagationDelay=0.000000E+000
|RECORD=2|OwnerIndex=76|OwnerPartId=1|FormalType=1|Electrical=4|PinConglomerate=56|PinLength=30|Location.X=948|Location.Y=987|Name=RS-232 RX|Designator=P8|PinPropagationDelay=0.000000E+000
|RECORD=41|OwnerIndex=76|IndexInSheet=25|OwnerPartId=-1|Location.X=798|Location.Y=901|Color=8388608|FontID=8|Text=RV-3049-C3|Name=VALUE
|RECORD=14|OwnerIndex=76|IsNotAccesible=T|IndexInSheet=26|OwnerPartId=2|Location.X=808|Location.Y=907|Corner.X=928|Corner.Y=1037|Color=128|AreaColor=11599871|IsSolid=T
|RECORD=2|OwnerIndex=76|OwnerPartId=2|FormalType=1|Electrical=4|PinConglomerate=58|PinLength=30|Location.X=808|Location.Y=1027|Name=PPS-IN 1+|Designator=1|PinPropagationDelay=0.000000E+000
|RECORD=2|OwnerIndex=76|OwnerPartId=2|FormalType=1|Electrical=4|PinConglomerate=56|PinLength=30|Location.X=928|Location.Y=1027|Name=USB DATA +|Designator=2|PinPropagationDelay=0.000000E+000
|RECORD=2|OwnerIndex=76|OwnerPartId=2|FormalType=1|Electrical=4|PinConglomerate=58|PinLength=30|Location.X=808|Location.Y=1017|Name=PPS-IN 1-|Designator=3|PinPropagationDelay=0.000000E+000
|RECORD=2|OwnerIndex=76|OwnerPartId=2|FormalType=1|Electrical=4|PinConglomerate=56|PinLength=30|Location.X=928|Location.Y=1017|Name=USB DATA -|Designator=4|PinPropagationDelay=0.000000E+000
|RECORD=2|OwnerIndex=76|OwnerPartId=2|FormalType=1|Electrical=4|PinConglomerate=58|PinLength=30|Location.X=808|Location.Y=1007|Name=PPS-IN 0+|Designator=5|PinPropagationDelay=0.000000E+000
|RECORD=2|OwnerIndex=76|OwnerPartId=2|FormalType=1|Electrical=4|PinConglomerate=56|PinLength=30|Location.X=928|Location.Y=1007|Name=USB POWER|Designator=6|PinPropagationDelay=0.000000E+000
|RECORD=2|OwnerIndex=76|OwnerPartId=2|FormalType=1|Electrical=4|PinConglomerate=58|PinLength=30|Location.X=808|Location.Y=997|Name=PPS-IN 0-|Designator=7|PinPropagationDelay=0.000000E+000
|RECORD=2|OwnerIndex=76|OwnerPartId=2|FormalType=1|Electrical=4|PinConglomerate=56|PinLength=30|Location.X=928|Location.Y=937|Name=GND|Designator=8|PinPropagationDelay=0.000000E+000
|RECORD=2|OwnerIndex=76|OwnerPartId=2|FormalType=1|Electrical=4|PinConglomerate=56|PinLength=30|Location.X=928|Location.Y=927|Name=GND|Designator=9|PinPropagationDelay=0.000000E+000
|RECORD=2|OwnerIndex=76|OwnerPartId=2|FormalType=1|Electrical=4|PinConglomerate=58|PinLength=30|Location.X=808|Location.Y=977|Name=NC|Designator=10|PinPropagationDelay=0.000000E+000
|RECORD=2|OwnerIndex=76|OwnerPartId=2|FormalType=1|Electrical=4|PinConglomerate=58|PinLength=30|Location.X=808|Location.Y=967|Name=NC|Designator=11|PinPropagationDelay=0.000000E+000
|RECORD=2|OwnerIndex=76|OwnerPartId=2|FormalType=1|Electrical=4|PinConglomerate=58|PinLength=30|Location.X=808|Location.Y=957|Name=NC|Designator=12|PinPropagationDelay=0.000000E+000
|RECORD=2|OwnerIndex=76|OwnerPartId=2|FormalType=1|Electrical=4|PinConglomerate=58|PinLength=30|Location.X=808|Location.Y=947|Name=NC|Designator=13|PinPropagationDelay=0.000000E+000
|RECORD=2|OwnerIndex=76|OwnerPartId=2|FormalType=1|Electrical=4|PinConglomerate=58|PinLength=30|Location.X=808|Location.Y=937|Name=NC|Designator=14|PinPropagationDelay=0.000000E+000
|RECORD=2|OwnerIndex=76|OwnerPartId=2|FormalType=1|Electrical=4|PinConglomerate=56|PinLength=30|Location.X=928|Location.Y=917|Name=GND|Designator=15|PinPropagationDelay=0.000000E+000
|RECORD=2|OwnerIndex=76|OwnerPartId=2|FormalType=1|Electrical=4|PinConglomerate=58|PinLength=30|Location.X=808|Location.Y=927|Name=NC|Designator=16|PinPropagationDelay=0.000000E+000
|RECORD=2|OwnerIndex=76|OwnerPartId=2|FormalType=1|Electrical=4|PinConglomerate=56|PinLength=30|Location.X=928|Location.Y=987|Name=PPS-OUT +|Designator=17|PinPropagationDelay=0.000000E+000
|RECORD=2|OwnerIndex=76|OwnerPartId=2|FormalType=1|Electrical=4|PinConglomerate=58|PinLength=30|Location.X=808|Location.Y=917|Name=NC|Designator=18|PinPropagationDelay=0.000000E+000
|RECORD=2|OwnerIndex=76|OwnerPartId=2|FormalType=1|Electrical=4|PinConglomerate=56|PinLength=30|Location.X=928|Location.Y=977|Name=PPS-OUT -|Designator=19|PinPropagationDelay=0.000000E+000
|RECORD=2|OwnerIndex=76|OwnerPartId=2|FormalType=1|Electrical=4|PinConglomerate=56|PinLength=30|Location.X=928|Location.Y=957|Name=ALARM|Designator=20|PinPropagationDelay=0.000000E+000
|RECORD=2|OwnerIndex=76|OwnerPartId=1|FormalType=1|Electrical=4|PinConglomerate=56|PinLength=30|Location.X=950|Location.Y=940|Name=PPS-IN|Designator=P9|PinPropagationDelay=0.000000E+000
|RECORD=2|OwnerIndex=76|OwnerPartId=1|FormalType=1|Electrical=4|PinConglomerate=56|PinLength=30|Location.X=950|Location.Y=930|Name=PPS-OUT|Designator=P10|PinPropagationDelay=0.000000E+000
|RECORD=34|OwnerIndex=76|IndexInSheet=-1|OwnerPartId=-1|Location.X=798|Location.Y=997|Color=8388608|FontID=1|Text=U10|Name=Designator|ReadOnlyState=1
|RECORD=41|OwnerIndex=76|IndexInSheet=-1|OwnerPartId=-1|Location.X=766|Location.Y=997|Color=8388608|FontID=1|IsHidden=T|Text=="MFG PART NUM"|Name=Comment
|RECORD=44|OwnerIndex=76
|RECORD=45|OwnerIndex=158|IndexInSheet=-1|ModelName=SA53|ModelType=PCBLIB|DatafileCount=1|ModelDatafileEntity0=SA53|ModelDatafileKind0=PCBLib|IsCurrent=T|IntegratedModel=T|DatabaseModel=T
|RECORD=46|OwnerIndex=159
|RECORD=48|OwnerIndex=159
|RECORD=1|LibReference=MAC-SA5X|ComponentDescription=MOD, MAC, MAC-SA5X, ATOMIC CLOCK|PartCount=3|DisplayModeCount=1|IndexInSheet=28|OwnerPartId=-1|Location.X=870|Location.Y=800|CurrentPartId=2|LibraryPath=*|SourceLibraryName=Modules.IntLib|TargetFileName=*|AreaColor=11599871|Color=128|PartIDLocked=F|DesignItemId=MAC-SA5X|AllPinCount=28
|RECORD=41|OwnerIndex=162|OwnerPartId=-1|Location.X=870|Location.Y=800|Color=8388608|FontID=8|IsHidden=T|Text=3/22/2006 1:36:44 PM|Name=MODIFY DATE
|RECORD=41|OwnerIndex=162|IndexInSheet=1|OwnerPartId=-1|Location.X=870|Location.Y=800|Color=8388608|FontID=8|IsHidden=T|Text=MAC-SA5X|Name=MFG PART NUM
|RECORD=41|OwnerIndex=162|IndexInSheet=2|OwnerPartId=-1|Location.X=838|Location.Y=832|Color=8388608|FontID=8|IsHidden=T|Text=MOD|Name=CATEGORY
|RECORD=41|OwnerIndex=162|IndexInSheet=3|OwnerPartId=-1|Location.X=838|Location.Y=832|Color=8388608|FontID=8|IsHidden=T|Name=DATE
|RECORD=41|OwnerIndex=162|IndexInSheet=4|OwnerPartId=-1|Location.X=838|Location.Y=832|Color=8388608|FontID=8|IsHidden=T|Text=MICROCHIP|Name=MFG NAME
|RECORD=41|OwnerIndex=162|IndexInSheet=5|OwnerPartId=-1|Location.X=838|Location.Y=832|Color=8388608|FontID=8|IsHidden=T|Text=85C|Name=MAXTEMP
|RECORD=41|OwnerIndex=162|IndexInSheet=6|OwnerPartId=-1|Location.X=838|Location.Y=832|Color=8388608|FontID=8|IsHidden=T|Text=-40C|Name=MINTEMP
|RECORD=41|OwnerIndex=162|IndexInSheet=7|OwnerPartId=-1|Location.X=838|Location.Y=832|Color=8388608|FontID=8|IsHidden=T|Text=AEC-Q200|Name=OTHER
|RECORD=41|OwnerIndex=162|IndexInSheet=8|OwnerPartId=-1|Location.X=838|Location.Y=832|Color=8388608|FontID=8|IsHidden=T|Text=ATOMIC CLOCK|Name=P1
|RECORD=41|OwnerIndex=162|IndexInSheet=9|OwnerPartId=-1|Location.X=838|Location.Y=832|Color=8388608|FontID=8|IsHidden=T|Name=P2
|RECORD=41|OwnerIndex=162|IndexInSheet=10|OwnerPartId=-1|Location.X=838|Location.Y=832|Color=8388608|FontID=8|IsHidden=T|Name=P3
|RECORD=41|OwnerIndex=162|IndexInSheet=11|OwnerPartId=-1|Location.X=838|Location.Y=832|Color=8388608|FontID=8|IsHidden=T|Name=SIZE
|RECORD=41|OwnerIndex=162|IndexInSheet=12|OwnerPartId=-1|Location.X=838|Location.Y=832|Color=8388608|FontID=8|IsHidden=T|Name=SUB
|RECORD=41|OwnerIndex=162|IndexInSheet=13|OwnerPartId=-1|Location.X=838|Location.Y=628|Color=8388608|FontID=1|IsHidden=T|Text=*|Name=SHEETPART
|RECORD=41|OwnerIndex=162|IndexInSheet=14|OwnerPartId=-1|Location.X=838|Location.Y=832|Color=8388608|FontID=1|IsHidden=T|Text=MOD, MAC, MAC-SA5X, ATOMIC CLOCK|Name=DESC
|RECORD=41|OwnerIndex=162|IndexInSheet=15|OwnerPartId=-1|Location.X=828|Location.Y=832|Color=8388608|FontID=1|IsHidden=T|Text=<V PART NUM>|Name=VELENTIUM PART NUM
|RECORD=14|OwnerIndex=162|IsNotAccesible=T|IndexInSheet=16|OwnerPartId=1|Location.X=800|Location.Y=770|Corner.X=950|Corner.Y=820|Color=128|AreaColor=11599871|IsSolid=T
|RECORD=2|OwnerIndex=162|OwnerPartId=1|FormalType=1|Electrical=4|PinConglomerate=58|PinLength=30|Location.X=800|Location.Y=810|Name=FREQ CTRL IN|Designator=P1|SwapIDPart=Ž&Ž||PinPropagationDelay=0.000000E+000
|RECORD=2|OwnerIndex=162|OwnerPartId=1|FormalType=1|Electrical=4|PinConglomerate=58|PinLength=30|Location.X=800|Location.Y=800|Name=GND (CASE)|Designator=P2|SwapIDPart=Ž&Ž||PinPropagationDelay=0.000000E+000
|RECORD=2|OwnerIndex=162|OwnerPartId=1|FormalType=1|Electrical=4|PinConglomerate=58|PinLength=30|Location.X=800|Location.Y=790|Name=RF OUT|Designator=P3|SwapIDPart=Ž&Ž||PinPropagationDelay=0.000000E+000
|RECORD=2|OwnerIndex=162|OwnerPartId=1|FormalType=1|Electrical=4|PinConglomerate=58|PinLength=30|Location.X=800|Location.Y=780|Name=GND (SUPPLY & SIGNAL)|Designator=P4|SwapIDPart=Ž&Ž||PinPropagationDelay=0.000000E+000
|RECORD=2|OwnerIndex=162|OwnerPartId=1|FormalType=1|Electrical=4|PinConglomerate=56|PinLength=30|Location.X=950|Location.Y=780|Name=VCC|Designator=P5|SwapIDPart=Ž&Ž||PinPropagationDelay=0.000000E+000
|RECORD=2|OwnerIndex=162|OwnerPartId=1|FormalType=1|Electrical=4|PinConglomerate=56|PinLength=30|Location.X=950|Location.Y=790|Name=BITE|Designator=P6|SwapIDPart=Ž&Ž||PinPropagationDelay=0.000000E+000
|RECORD=2|OwnerIndex=162|OwnerPartId=1|FormalType=1|Electrical=4|PinConglomerate=56|PinLength=30|Location.X=950|Location.Y=800|Name=RS-232 TX|Designator=P7|SwapIDPart=Ž&Ž||PinPropagationDelay=0.000000E+000
|RECORD=2|OwnerIndex=162|OwnerPartId=1|FormalType=1|Electrical=4|PinConglomerate=56|PinLength=30|Location.X=950|Location.Y=810|Name=RS-232 RX|Designator=P8|SwapIDPart=Ž&Ž||PinPropagationDelay=0.000000E+000
|RECORD=41|OwnerIndex=162|IndexInSheet=25|OwnerPartId=-1|Location.X=810|Location.Y=718|Color=8388608|FontID=8|Text=RV-3049-C3|Name=VALUE
|RECORD=14|OwnerIndex=162|IsNotAccesible=T|IndexInSheet=26|OwnerPartId=2|Location.X=810|Location.Y=730|Corner.X=930|Corner.Y=860|Color=128|AreaColor=11599871|IsSolid=T
|RECORD=2|OwnerIndex=162|OwnerPartId=2|FormalType=1|Electrical=4|PinConglomerate=58|PinLength=30|Location.X=810|Location.Y=850|Name=PPS-IN 1+|Designator=1|SwapIDPart=Ž&Ž||PinPropagationDelay=0.000000E+000
|RECORD=2|OwnerIndex=162|OwnerPartId=2|FormalType=1|Electrical=4|PinConglomerate=56|PinLength=30|Location.X=930|Location.Y=850|Name=USB DATA +|Designator=2|SwapIDPart=Ž&Ž||PinPropagationDelay=0.000000E+000
|RECORD=2|OwnerIndex=162|OwnerPartId=2|FormalType=1|Electrical=4|PinConglomerate=58|PinLength=30|Location.X=810|Location.Y=840|Name=PPS-IN 1-|Designator=3|SwapIDPart=Ž&Ž||PinPropagationDelay=0.000000E+000
|RECORD=2|OwnerIndex=162|OwnerPartId=2|FormalType=1|Electrical=4|PinConglomerate=56|PinLength=30|Location.X=930|Location.Y=840|Name=USB DATA -|Designator=4|SwapIDPart=Ž&Ž||PinPropagationDelay=0.000000E+000
|RECORD=2|OwnerIndex=162|OwnerPartId=2|FormalType=1|Electrical=4|PinConglomerate=58|PinLength=30|Location.X=810|Location.Y=830|Name=PPS-IN 0+|Designator=5|SwapIDPart=Ž&Ž||PinPropagationDelay=0.000000E+000
|RECORD=2|OwnerIndex=162|OwnerPartId=2|FormalType=1|Electrical=4|PinConglomerate=56|PinLength=30|Location.X=930|Location.Y=830|Name=USB POWER|Designator=6|SwapIDPart=Ž&Ž||PinPropagationDelay=0.000000E+000
|RECORD=2|OwnerIndex=162|OwnerPartId=2|FormalType=1|Electrical=4|PinConglomerate=58|PinLength=30|Location.X=810|Location.Y=820|Name=PPS-IN 0-|Designator=7|SwapIDPart=Ž&Ž||PinPropagationDelay=0.000000E+000
|RECORD=2|OwnerIndex=162|OwnerPartId=2|FormalType=1|Electrical=4|PinConglomerate=56|PinLength=30|Location.X=930|Location.Y=760|Name=GND|Designator=8|SwapIDPart=Ž&Ž||PinPropagationDelay=0.000000E+000
|RECORD=2|OwnerIndex=162|OwnerPartId=2|FormalType=1|Electrical=4|PinConglomerate=56|PinLength=30|Location.X=930|Location.Y=750|Name=GND|Designator=9|SwapIDPart=Ž&Ž||PinPropagationDelay=0.000000E+000
|RECORD=2|OwnerIndex=162|OwnerPartId=2|FormalType=1|Electrical=4|PinConglomerate=58|PinLength=30|Location.X=810|Location.Y=800|Name=NC|Designator=10|SwapIDPart=Ž&Ž||PinPropagationDelay=0.000000E+000
|RECORD=2|OwnerIndex=162|OwnerPartId=2|FormalType=1|Electrical=4|PinConglomerate=58|PinLength=30|Location.X=810|Location.Y=790|Name=NC|Designator=11|SwapIDPart=Ž&Ž||PinPropagationDelay=0.000000E+000
|RECORD=2|OwnerIndex=162|OwnerPartId=2|FormalType=1|Electrical=4|PinConglomerate=58|PinLength=30|Location.X=810|Location.Y=780|Name=NC|Designator=12|SwapIDPart=Ž&Ž||PinPropagationDelay=0.000000E+000
|RECORD=2|OwnerIndex=162|OwnerPartId=2|FormalType=1|Electrical=4|PinConglomerate=58|PinLength=30|Location.X=810|Location.Y=770|Name=NC|Designator=13|SwapIDPart=Ž&Ž||PinPropagationDelay=0.000000E+000
|RECORD=2|OwnerIndex=162|OwnerPartId=2|FormalType=1|Electrical=4|PinConglomerate=58|PinLength=30|Location.X=810|Location.Y=760|Name=NC|Designator=14|SwapIDPart=Ž&Ž||PinPropagationDelay=0.000000E+000
|RECORD=2|OwnerIndex=162|OwnerPartId=2|FormalType=1|Electrical=4|PinConglomerate=56|PinLength=30|Location.X=930|Location.Y=740|Name=GND|Designator=15|SwapIDPart=Ž&Ž||PinPropagationDelay=0.000000E+000
|RECORD=2|OwnerIndex=162|OwnerPartId=2|FormalType=1|Electrical=4|PinConglomerate=58|PinLength=30|Location.X=810|Location.Y=750|Name=NC|Designator=16|SwapIDPart=Ž&Ž||PinPropagationDelay=0.000000E+000
|RECORD=2|OwnerIndex=162|OwnerPartId=2|FormalType=1|Electrical=4|PinConglomerate=56|PinLength=30|Location.X=930|Location.Y=810|Name=PPS-OUT +|Designator=17|SwapIDPart=Ž&Ž||PinPropagationDelay=0.000000E+000
|RECORD=2|OwnerIndex=162|OwnerPartId=2|FormalType=1|Electrical=4|PinConglomerate=58|PinLength=30|Location.X=810|Location.Y=740|Name=NC|Designator=18|SwapIDPart=Ž&Ž||PinPropagationDelay=0.000000E+000
|RECORD=2|OwnerIndex=162|OwnerPartId=2|FormalType=1|Electrical=4|PinConglomerate=56|PinLength=30|Location.X=930|Location.Y=800|Name=PPS-OUT -|Designator=19|SwapIDPart=Ž&Ž||PinPropagationDelay=0.000000E+000
|RECORD=2|OwnerIndex=162|OwnerPartId=2|FormalType=1|Electrical=4|PinConglomerate=56|PinLength=30|Location.X=930|Location.Y=780|Name=ALARM|Designator=20|SwapIDPart=Ž&Ž||PinPropagationDelay=0.000000E+000
|RECORD=34|OwnerIndex=162|IndexInSheet=-1|OwnerPartId=-1|Location.X=810|Location.Y=860|Color=8388608|FontID=1|Text=U10|Name=Designator|ReadOnlyState=1
|RECORD=41|OwnerIndex=162|IndexInSheet=-1|OwnerPartId=-1|Location.X=890|Location.Y=760|Color=8388608|FontID=1|IsHidden=T|Text=="MFG PART NUM"|Name=Comment
|RECORD=44|OwnerIndex=162
|RECORD=45|OwnerIndex=240|IndexInSheet=-1|ModelName=SA53|ModelType=PCBLIB|DatafileCount=1|ModelDatafileEntity0=SA53|ModelDatafileKind0=PCBLib|IsCurrent=T|IntegratedModel=T|DatabaseModel=T
|RECORD=46|OwnerIndex=241
|RECORD=48|OwnerIndex=241
|RECORD=1|LibReference=CAP|ComponentDescription=C0603X104K5RACAUTO|PartCount=2|DisplayModeCount=2|IndexInSheet=29|OwnerPartId=-1|Location.X=1330|Location.Y=930|Orientation=1|CurrentPartId=1|SourceLibraryName=Altium Content Vault|TargetFileName=*|AreaColor=11599871|Color=128|PartIDLocked=F|DesignItemId=CMP-2006-00003-1|AllPinCount=2
|RECORD=2|OwnerIndex=244|OwnerPartId=1|OwnerPartDisplayMode=1|FormalType=1|Electrical=4|PinConglomerate=35|PinLength=10|Location.X=1340|Location.Y=930|Name=1|Designator=1|PinPropagationDelay=0.000000E+000
|RECORD=2|OwnerIndex=244|OwnerPartId=1|OwnerPartDisplayMode=1|FormalType=1|Electrical=4|PinConglomerate=33|PinLength=10|Location.X=1340|Location.Y=940|Name=2|Designator=2|PinPropagationDelay=0.000000E+000
|RECORD=13|OwnerIndex=244|IsNotAccesible=T|IndexInSheet=2|OwnerPartId=1|OwnerPartDisplayMode=1|Location.X=1348|Location.Y=930|Corner.X=1332|Corner.Y=930|LineWidth=1|Color=16711680
|RECORD=13|OwnerIndex=244|IsNotAccesible=T|IndexInSheet=3|OwnerPartId=1|OwnerPartDisplayMode=1|Location.X=1340|Location.Y=934|Corner.X=1340|Corner.Y=940|LineWidth=1|Color=16711680
|RECORD=12|OwnerIndex=244|IsNotAccesible=T|IndexInSheet=4|OwnerPartId=1|OwnerPartDisplayMode=1|Location.X=1340|Location.Y=950|Radius=16|LineWidth=1|StartAngle=241.000|EndAngle=270.000|Color=16711680
|RECORD=12|OwnerIndex=244|IsNotAccesible=T|IndexInSheet=5|OwnerPartId=1|OwnerPartDisplayMode=1|Location.X=1340|Location.Y=950|Radius=16|LineWidth=1|StartAngle=270.000|EndAngle=299.000|Color=16711680
|RECORD=2|OwnerIndex=244|OwnerPartId=1|FormalType=1|Electrical=4|PinConglomerate=35|PinLength=10|Location.X=1340|Location.Y=930|Name=1|Designator=1|PinPropagationDelay=0.000000E+000
|RECORD=2|OwnerIndex=244|OwnerPartId=1|FormalType=1|Electrical=4|PinConglomerate=33|PinLength=10|Location.X=1340|Location.Y=940|Name=2|Designator=2|PinPropagationDelay=0.000000E+000
|RECORD=13|OwnerIndex=244|IsNotAccesible=T|IndexInSheet=8|OwnerPartId=1|Location.X=1332|Location.Y=937|Corner.X=1348|Corner.Y=937|LineWidth=1|Color=16711680
|RECORD=13|OwnerIndex=244|IsNotAccesible=T|IndexInSheet=9|OwnerPartId=1|Location.X=1348|Location.Y=933|Corner.X=1332|Corner.Y=933|LineWidth=1|Color=16711680
|RECORD=6|OwnerIndex=244|IsNotAccesible=T|IndexInSheet=10|OwnerPartId=1|LineWidth=1|Color=16711680|LocationCount=2|X1=1340|Y1=930|X2=1340|Y2=933
|RECORD=6|OwnerIndex=244|IsNotAccesible=T|IndexInSheet=11|OwnerPartId=1|LineWidth=1|Color=16711680|LocationCount=2|X1=1340|Y1=940|X2=1340|Y2=937
|RECORD=41|OwnerIndex=244|IndexInSheet=12|OwnerPartId=-1|Location.X=1331|Location.Y=952|Color=8388608|FontID=1|IsHidden=T|Text=Kemet|Name=Manufacturer
|RECORD=41|OwnerIndex=244|IndexInSheet=13|OwnerPartId=-1|Location.X=1331|Location.Y=952|Color=8388608|FontID=1|IsHidden=T|Text=C0603X104K5RACAUTO|Name=Part Number
|RECORD=34|OwnerIndex=244|IndexInSheet=-1|OwnerPartId=-1|Location.X=1349|Location.Y=931|Color=8388608|FontID=1|Text=C63|Name=Designator|ReadOnlyState=1
|RECORD=41|OwnerIndex=244|IndexInSheet=-1|OwnerPartId=-1|Location.X=1349|Location.Y=921|Color=8388608|FontID=1|Text=0.1uF|Name=Comment
|RECORD=44|OwnerIndex=244
|RECORD=45|OwnerIndex=265|IndexInSheet=-1|Description=Chip Capacitor, 2-Leads, Body 1.60x0.80mm, IPC Low Density|UseComponentLibrary=T|ModelName=CAPC1608X87X45ML20T05|ModelType=PCBLIB|DatafileCount=1|ModelDatafileEntity0=CAPC1608X87X45ML20T05|ModelDatafileKind0=PCBLib|IsCurrent=T|DatalinksLocked=T|DatabaseDatalinksLocked=T
|RECORD=46|OwnerIndex=266
|RECORD=48|OwnerIndex=266
|RECORD=41|OwnerIndex=268|IndexInSheet=-1|OwnerPartId=-1|Color=8388608|FontID=1|Text=2D|Name=Available Preview Images
|RECORD=45|OwnerIndex=265|IndexInSheet=-1|Description=Chip Capacitor, 2-Leads, Body 1.60x0.80mm, IPC High Density|UseComponentLibrary=T|ModelName=CAPC1608X87X45LL20T05|ModelType=PCBLIB|DatafileCount=1|ModelDatafileEntity0=CAPC1608X87X45LL20T05|ModelDatafileKind0=PCBLib|DatalinksLocked=T|DatabaseDatalinksLocked=T
|RECORD=46|OwnerIndex=270
|RECORD=48|OwnerIndex=270
|RECORD=41|OwnerIndex=272|IndexInSheet=-1|OwnerPartId=-1|Color=8388608|FontID=1|Text=2D|Name=Available Preview Images
|RECORD=45|OwnerIndex=265|IndexInSheet=-1|Description=Chip Capacitor, 2-Leads, Body 1.60x0.80mm, IPC Medium Density|UseComponentLibrary=T|ModelName=CAPC1608X87X45NL20T05|ModelType=PCBLIB|DatafileCount=1|ModelDatafileEntity0=CAPC1608X87X45NL20T05|ModelDatafileKind0=PCBLib|DatalinksLocked=T|DatabaseDatalinksLocked=T
|RECORD=46|OwnerIndex=274
|RECORD=48|OwnerIndex=274
|RECORD=41|OwnerIndex=276|IndexInSheet=-1|OwnerPartId=-1|Color=8388608|FontID=1|Text=2D|Name=Available Preview Images
|RECORD=41|IndexInSheet=30|OwnerPartId=-1|Color=8388608|FontID=1|IsHidden=T|Name=ConfigurationParameters|ReadOnlyState=1
|RECORD=41|IndexInSheet=31|OwnerPartId=-1|Color=8388608|FontID=1|IsHidden=T|Name=ConfiguratorName|ReadOnlyState=1
|RECORD=41|IndexInSheet=32|OwnerPartId=-1|Color=8388608|FontID=1|IsHidden=T|Name=VersionControl_RevNumber|ReadOnlyState=1
|RECORD=41|IndexInSheet=33|OwnerPartId=-1|Color=8388608|FontID=1|IsHidden=T|Name=IsUserConfigurable|ReadOnlyState=1
|RECORD=41|IndexInSheet=34|OwnerPartId=-1|Color=8388608|FontID=1|IsHidden=T|Name=VersionControl_ProjFolderRevNumber|ReadOnlyState=1
|RECORD=41|IndexInSheet=35|OwnerPartId=-1|Color=8388608|FontID=1|IsHidden=T|Name=SPICEModelCache|ReadOnlyState=1
|RECORD=1|LibReference=IN-LNDRV-DS90LV027AHM|ComponentDescription=Automotive LVDS Dual Differential Driver, 8-pin Narrow SOIC|PartCount=2|DisplayModeCount=1|IndexInSheet=36|OwnerPartId=-1|Location.X=1130|Location.Y=300|CurrentPartId=1|LibraryPath=*|SourceLibraryName=Altium Content Vault|TargetFileName=*|AreaColor=11599871|Color=128|PartIDLocked=T|DesignItemId=CMP-0058-01000-2|AllPinCount=8
|RECORD=14|OwnerIndex=284|IsNotAccesible=T|OwnerPartId=1|Location.X=1130|Location.Y=220|Corner.X=1200|Corner.Y=300|Color=128|AreaColor=11599871|IsSolid=T
|RECORD=2|OwnerIndex=284|OwnerPartId=1|FormalType=1|PinConglomerate=58|PinLength=20|Location.X=1130|Location.Y=290|Name=DI1|Designator=2|SwapIDPart=Ž&Ž||PinPropagationDelay=0.000000E+000
|RECORD=2|OwnerIndex=284|OwnerPartId=1|FormalType=1|PinConglomerate=58|PinLength=20|Location.X=1130|Location.Y=260|Name=DI2|Designator=3|SwapIDPart=Ž&Ž||PinPropagationDelay=0.000000E+000
|RECORD=2|OwnerIndex=284|OwnerPartId=1|FormalType=1|Electrical=2|PinConglomerate=56|PinLength=20|Location.X=1200|Location.Y=290|Name=DO+1|Designator=7|SwapIDPart=Ž&Ž||PinPropagationDelay=0.000000E+000
|RECORD=2|OwnerIndex=284|OwnerPartId=1|FormalType=1|Electrical=2|PinConglomerate=56|PinLength=20|Location.X=1200|Location.Y=260|Name=DO+2|Designator=6|SwapIDPart=Ž&Ž||PinPropagationDelay=0.000000E+000
|RECORD=2|OwnerIndex=284|OwnerPartId=1|FormalType=1|Electrical=2|PinConglomerate=56|PinLength=20|Location.X=1200|Location.Y=280|Name=DO-1|Designator=8|SwapIDPart=Ž&Ž||PinPropagationDelay=0.000000E+000
|RECORD=2|OwnerIndex=284|OwnerPartId=1|FormalType=1|Electrical=2|PinConglomerate=56|PinLength=20|Location.X=1200|Location.Y=250|Name=DO-2|Designator=5|SwapIDPart=Ž&Ž||PinPropagationDelay=0.000000E+000
|RECORD=2|OwnerIndex=284|OwnerPartId=1|FormalType=1|Electrical=7|PinConglomerate=56|PinLength=20|Location.X=1200|Location.Y=230|Name=GND|Designator=4|SwapIDPart=Ž&Ž||PinPropagationDelay=0.000000E+000
|RECORD=2|OwnerIndex=284|OwnerPartId=1|FormalType=1|Electrical=7|PinConglomerate=58|PinLength=20|Location.X=1130|Location.Y=230|Name=VCC|Designator=1|SwapIDPart=Ž&Ž||PinPropagationDelay=0.000000E+000
|RECORD=41|OwnerIndex=284|IndexInSheet=9|OwnerPartId=-1|Location.X=1108|Location.Y=300|Color=8388608|FontID=1|IsHidden=T|Text=Oct-2008|Name=DatasheetVersion
|RECORD=41|OwnerIndex=284|IndexInSheet=10|OwnerPartId=-1|Location.X=1108|Location.Y=300|Color=8388608|FontID=1|IsHidden=T|Text=8|Name=PinCount
|RECORD=41|OwnerIndex=284|IndexInSheet=11|OwnerPartId=-1|Location.X=1108|Location.Y=300|Color=8388608|FontID=1|IsHidden=T|Text=Component URLs added|Name=RevisionNote
|RECORD=41|OwnerIndex=284|IndexInSheet=12|OwnerPartId=-1|Location.X=1108|Location.Y=300|Color=8388608|FontID=1|IsHidden=T|Text=SOIC127P600-8|Name=Code_IPC
|RECORD=41|OwnerIndex=284|IndexInSheet=13|OwnerPartId=-1|Location.X=1108|Location.Y=300|Color=8388608|FontID=1|IsHidden=T|Text=National Semiconductor|Name=Manufacturer
|RECORD=41|OwnerIndex=284|IndexInSheet=14|OwnerPartId=-1|Location.X=1108|Location.Y=300|Color=8388608|FontID=1|IsHidden=T|Text=NSZXTT*90LV0*27AQM|Name=PackageTopMarking
|RECORD=41|OwnerIndex=284|IndexInSheet=15|OwnerPartId=-1|Location.X=1108|Location.Y=300|Color=8388608|FontID=1|IsHidden=T|Text=Interface IC|Name=CompType
|RECORD=41|OwnerIndex=284|IndexInSheet=16|OwnerPartId=-1|Location.X=1108|Location.Y=300|Color=8388608|FontID=7|IsHidden=T|Text=http://www.national.com/ds/DS/DS90LV027AQ.pdf|Name=ComponentLink1URL
|RECORD=41|OwnerIndex=284|IndexInSheet=17|OwnerPartId=-1|Location.X=1108|Location.Y=300|Color=8388608|FontID=1|IsHidden=T|Text=M08A Package Page|Name=ComponentLink3Description
|RECORD=41|OwnerIndex=284|IndexInSheet=18|OwnerPartId=-1|Location.X=1108|Location.Y=300|Color=8388608|FontID=1|IsHidden=T|Text=SOIC Narrow, 4.9 x 3.9 x 1.45mm, 8 Lead, 1.27mm Pitch|Name=PackageDescription
|RECORD=41|OwnerIndex=284|IndexInSheet=19|OwnerPartId=-1|Location.X=1108|Location.Y=300|Color=8388608|FontID=1|IsHidden=T|Text=DS90LV027AQ Web Page|Name=ComponentLink2Description
|RECORD=41|OwnerIndex=284|IndexInSheet=20|OwnerPartId=-1|Location.X=1108|Location.Y=300|Color=8388608|FontID=7|IsHidden=T|Text=http://www.national.com/pf/DS/DS90LV027AQ.html|Name=ComponentLink2URL
|RECORD=41|OwnerIndex=284|IndexInSheet=21|OwnerPartId=-1|Location.X=1108|Location.Y=300|Color=8388608|FontID=1|IsHidden=T|Text=Y|Name=RoHS
|RECORD=41|OwnerIndex=284|IndexInSheet=22|OwnerPartId=-1|Location.X=1108|Location.Y=300|Color=8388608|FontID=1|IsHidden=T|Text=N|Name=PowerWise
|RECORD=41|OwnerIndex=284|IndexInSheet=23|OwnerPartId=-1|Location.X=1108|Location.Y=300|Color=8388608|FontID=1|IsHidden=T|Text=MS-012-AA|Name=Code_JEDEC
|RECORD=41|OwnerIndex=284|IndexInSheet=24|OwnerPartId=-1|Location.X=1108|Location.Y=300|Color=8388608|FontID=1|IsHidden=T|Text=M08A|Name=PackageReference
|RECORD=41|OwnerIndex=284|IndexInSheet=25|OwnerPartId=-1|Location.X=1108|Location.Y=300|Color=8388608|FontID=1|IsHidden=T|Text=revM, May-2009|Name=PackageVersion
|RECORD=41|OwnerIndex=284|IndexInSheet=26|OwnerPartId=-1|Location.X=1108|Location.Y=300|Color=8388608|FontID=1|IsHidden=T|Text=DS90LV027AQ Datasheet|Name=ComponentLink1Description
|RECORD=41|OwnerIndex=284|IndexInSheet=27|OwnerPartId=-1|Location.X=1108|Location.Y=300|Color=8388608|FontID=7|IsHidden=T|Text=http://www.national.com/packaging/folders/m08a.html|Name=ComponentLink3URL
|RECORD=34|OwnerIndex=284|IndexInSheet=-1|OwnerPartId=-1|Location.X=1130|Location.Y=300|Color=8388608|FontID=1|Text=U3|Name=Designator|ReadOnlyState=1
|RECORD=41|OwnerIndex=284|IndexInSheet=-1|OwnerPartId=-1|Location.X=1130|Location.Y=210|Color=8388608|FontID=1|Text=DS90LV027AQMA|Name=Comment
|RECORD=44|OwnerIndex=284
|RECORD=45|OwnerIndex=323|IndexInSheet=-1|Description=SOIC, 8-Leads, Body 4.9x3.9mm, Pitch 1.27mm, IPC Medium Density|UseComponentLibrary=T|ModelName=M08A_N|ModelType=PCBLIB|DatafileCount=1|ModelDatafileEntity0=M08A_N|ModelDatafileKind0=PCBLib|IsCurrent=T|DatalinksLocked=T|DatabaseDatalinksLocked=T
|RECORD=46|OwnerIndex=324
|RECORD=48|OwnerIndex=324
|RECORD=41|OwnerIndex=326|IndexInSheet=-1|OwnerPartId=-1|Color=8388608|FontID=1|IsHidden=T|Text=2D|Name=Available Preview Images
|RECORD=45|OwnerIndex=323|IndexInSheet=-1|Description=SOIC, 8-Leads, Body 4.9x3.9mm, Pitch 1.27mm, IPC Low Density|UseComponentLibrary=T|ModelName=M08A_M|ModelType=PCBLIB|DatafileCount=1|ModelDatafileEntity0=M08A_M|ModelDatafileKind0=PCBLib|DatalinksLocked=T|DatabaseDatalinksLocked=T
|RECORD=46|OwnerIndex=328
|RECORD=48|OwnerIndex=328
|RECORD=41|OwnerIndex=330|IndexInSheet=-1|OwnerPartId=-1|Color=8388608|FontID=1|IsHidden=T|Text=2D|Name=Available Preview Images
|RECORD=45|OwnerIndex=323|IndexInSheet=-1|Description=SOIC, 8-Leads, Body 4.9x3.9mm, Pitch 1.27mm, IPC High Density|UseComponentLibrary=T|ModelName=M08A_L|ModelType=PCBLIB|DatafileCount=1|ModelDatafileEntity0=M08A_L|ModelDatafileKind0=PCBLib|DatalinksLocked=T|DatabaseDatalinksLocked=T
|RECORD=46|OwnerIndex=332
|RECORD=48|OwnerIndex=332
|RECORD=41|OwnerIndex=334|IndexInSheet=-1|OwnerPartId=-1|Color=8388608|FontID=1|IsHidden=T|Text=2D|Name=Available Preview Images
|RECORD=1|LibReference=IN-LNRX-DS90LV028AHM|ComponentDescription=Automotive LVDS Dual Differential Line Receiver, 8-pin Narrow SOIC|PartCount=2|DisplayModeCount=1|IndexInSheet=37|OwnerPartId=-1|Location.X=340|Location.Y=280|CurrentPartId=1|LibraryPath=*|SourceLibraryName=Altium Content Vault|TargetFileName=*|AreaColor=11599871|Color=128|PartIDLocked=T|DesignItemId=CMP-0058-01010-2|AllPinCount=8
|RECORD=14|OwnerIndex=336|IsNotAccesible=T|OwnerPartId=1|Location.X=340|Location.Y=200|Corner.X=420|Corner.Y=280|Color=128|AreaColor=11599871|IsSolid=T
|RECORD=2|OwnerIndex=336|OwnerPartId=1|FormalType=1|PinConglomerate=58|PinLength=20|Location.X=340|Location.Y=260|Name=RIN1-|Designator=1|SwapIDPart=Ž&Ž||PinPropagationDelay=0.000000E+000
|RECORD=2|OwnerIndex=336|OwnerPartId=1|FormalType=1|PinConglomerate=58|PinLength=20|Location.X=340|Location.Y=270|Name=RIN1+|Designator=2|SwapIDPart=Ž&Ž||PinPropagationDelay=0.000000E+000
|RECORD=2|OwnerIndex=336|OwnerPartId=1|FormalType=1|PinConglomerate=58|PinLength=20|Location.X=340|Location.Y=240|Name=RIN2+|Designator=3|SwapIDPart=Ž&Ž||PinPropagationDelay=0.000000E+000
|RECORD=2|OwnerIndex=336|OwnerPartId=1|FormalType=1|PinConglomerate=58|PinLength=20|Location.X=340|Location.Y=230|Name=RIN2-|Designator=4|SwapIDPart=Ž&Ž||PinPropagationDelay=0.000000E+000
|RECORD=2|OwnerIndex=336|OwnerPartId=1|FormalType=1|Electrical=7|PinConglomerate=56|PinLength=20|Location.X=420|Location.Y=210|Name=GND|Designator=5|SwapIDPart=Ž&Ž||PinPropagationDelay=0.000000E+000
|RECORD=2|OwnerIndex=336|OwnerPartId=1|FormalType=1|Electrical=2|PinConglomerate=56|PinLength=20|Location.X=420|Location.Y=240|Name=ROUT2|Designator=6|SwapIDPart=Ž&Ž||PinPropagationDelay=0.000000E+000
|RECORD=2|OwnerIndex=336|OwnerPartId=1|FormalType=1|Electrical=2|PinConglomerate=56|PinLength=20|Location.X=420|Location.Y=270|Name=ROUT1|Designator=7|SwapIDPart=Ž&Ž||PinPropagationDelay=0.000000E+000
|RECORD=2|OwnerIndex=336|OwnerPartId=1|FormalType=1|Electrical=7|PinConglomerate=58|PinLength=20|Location.X=340|Location.Y=210|Name=VCC|Designator=8|SwapIDPart=Ž&Ž||PinPropagationDelay=0.000000E+000
|RECORD=41|OwnerIndex=336|IndexInSheet=9|OwnerPartId=-1|Location.X=318|Location.Y=280|Color=8388608|FontID=1|IsHidden=T|Text=National Semiconductor|Name=Manufacturer
|RECORD=41|OwnerIndex=336|IndexInSheet=10|OwnerPartId=-1|Location.X=318|Location.Y=280|Color=8388608|FontID=1|IsHidden=T|Text=Oct-2008|Name=DatasheetVersion
|RECORD=41|OwnerIndex=336|IndexInSheet=11|OwnerPartId=-1|Location.X=318|Location.Y=280|Color=8388608|FontID=1|IsHidden=T|Text=N|Name=PowerWise
|RECORD=41|OwnerIndex=336|IndexInSheet=12|OwnerPartId=-1|Location.X=318|Location.Y=280|Color=8388608|FontID=1|IsHidden=T|Text=M08A|Name=PackageReference
|RECORD=41|OwnerIndex=336|IndexInSheet=13|OwnerPartId=-1|Location.X=318|Location.Y=280|Color=8388608|FontID=1|IsHidden=T|Text=Component URLs added|Name=RevisionNote
|RECORD=41|OwnerIndex=336|IndexInSheet=14|OwnerPartId=-1|Location.X=318|Location.Y=280|Color=8388608|FontID=1|IsHidden=T|Text=MS-012-AA|Name=Code_JEDEC
|RECORD=41|OwnerIndex=336|IndexInSheet=15|OwnerPartId=-1|Location.X=318|Location.Y=280|Color=8388608|FontID=1|IsHidden=T|Text=revM, May-2009|Name=PackageVersion
|RECORD=41|OwnerIndex=336|IndexInSheet=16|OwnerPartId=-1|Location.X=318|Location.Y=280|Color=8388608|FontID=7|IsHidden=T|Text=http://www.national.com/ds/DS/DS90LV028AQ.pdf|Name=ComponentLink1URL
|RECORD=41|OwnerIndex=336|IndexInSheet=17|OwnerPartId=-1|Location.X=318|Location.Y=280|Color=8388608|FontID=1|IsHidden=T|Text=8|Name=PinCount
|RECORD=41|OwnerIndex=336|IndexInSheet=18|OwnerPartId=-1|Location.X=318|Location.Y=280|Color=8388608|FontID=1|IsHidden=T|Text=M08A Package Page|Name=ComponentLink3Description
|RECORD=41|OwnerIndex=336|IndexInSheet=19|OwnerPartId=-1|Location.X=318|Location.Y=280|Color=8388608|FontID=1|IsHidden=T|Text=DS90LV028AQ Datasheet|Name=ComponentLink1Description
|RECORD=41|OwnerIndex=336|IndexInSheet=20|OwnerPartId=-1|Location.X=318|Location.Y=280|Color=8388608|FontID=1|IsHidden=T|Text=SOIC127P600-8|Name=Code_IPC
|RECORD=41|OwnerIndex=336|IndexInSheet=21|OwnerPartId=-1|Location.X=318|Location.Y=280|Color=8388608|FontID=1|IsHidden=T|Text=Y|Name=RoHS
|RECORD=41|OwnerIndex=336|IndexInSheet=22|OwnerPartId=-1|Location.X=318|Location.Y=280|Color=8388608|FontID=7|IsHidden=T|Text=http://www.national.com/pf/DS/DS90LV028AQ.html|Name=ComponentLink2URL
|RECORD=41|OwnerIndex=336|IndexInSheet=23|OwnerPartId=-1|Location.X=318|Location.Y=280|Color=8388608|FontID=1|IsHidden=T|Text=NSZXTT*90LV0*28AQM|Name=PackageTopMarking
|RECORD=41|OwnerIndex=336|IndexInSheet=24|OwnerPartId=-1|Location.X=318|Location.Y=280|Color=8388608|FontID=1|IsHidden=T|Text=SOIC Narrow, 4.9 x 3.9 x 1.45mm, 8 Lead, 1.27mm Pitch|Name=PackageDescription
|RECORD=41|OwnerIndex=336|IndexInSheet=25|OwnerPartId=-1|Location.X=318|Location.Y=280|Color=8388608|FontID=1|IsHidden=T|Text=DS90LV028AQ Web Page|Name=ComponentLink2Description
|RECORD=41|OwnerIndex=336|IndexInSheet=26|OwnerPartId=-1|Location.X=318|Location.Y=280|Color=8388608|FontID=7|IsHidden=T|Text=http://www.national.com/packaging/folders/m08a.html|Name=ComponentLink3URL
|RECORD=41|OwnerIndex=336|IndexInSheet=27|OwnerPartId=-1|Location.X=318|Location.Y=280|Color=8388608|FontID=1|IsHidden=T|Text=Interface IC|Name=CompType
|RECORD=34|OwnerIndex=336|IndexInSheet=-1|OwnerPartId=-1|Location.X=340|Location.Y=280|Color=8388608|FontID=1|Text=U4|Name=Designator|ReadOnlyState=1
|RECORD=41|OwnerIndex=336|IndexInSheet=-1|OwnerPartId=-1|Location.X=340|Location.Y=190|Color=8388608|FontID=1|Text=DS90LV028AQMA|Name=Comment
|RECORD=44|OwnerIndex=336
|RECORD=45|OwnerIndex=375|IndexInSheet=-1|Description=SOIC, 8-Leads, Body 4.9x3.9mm, Pitch 1.27mm, IPC High Density|UseComponentLibrary=T|ModelName=M08A_L|ModelType=PCBLIB|DatafileCount=1|ModelDatafileEntity0=M08A_L|ModelDatafileKind0=PCBLib|IsCurrent=T|DatalinksLocked=T|DatabaseDatalinksLocked=T
|RECORD=46|OwnerIndex=376
|RECORD=48|OwnerIndex=376
|RECORD=41|OwnerIndex=378|IndexInSheet=-1|OwnerPartId=-1|Color=8388608|FontID=1|IsHidden=T|Text=2D|Name=Available Preview Images
|RECORD=45|OwnerIndex=375|IndexInSheet=-1|Description=SOIC, 8-Leads, Body 4.9x3.9mm, Pitch 1.27mm, IPC Low Density|UseComponentLibrary=T|ModelName=M08A_M|ModelType=PCBLIB|DatafileCount=1|ModelDatafileEntity0=M08A_M|ModelDatafileKind0=PCBLib|DatalinksLocked=T|DatabaseDatalinksLocked=T
|RECORD=46|OwnerIndex=380
|RECORD=48|OwnerIndex=380
|RECORD=41|OwnerIndex=382|IndexInSheet=-1|OwnerPartId=-1|Color=8388608|FontID=1|IsHidden=T|Text=2D|Name=Available Preview Images
|RECORD=45|OwnerIndex=375|IndexInSheet=-1|Description=SOIC, 8-Leads, Body 4.9x3.9mm, Pitch 1.27mm, IPC Medium Density|UseComponentLibrary=T|ModelName=M08A_N|ModelType=PCBLIB|DatafileCount=1|ModelDatafileEntity0=M08A_N|ModelDatafileKind0=PCBLib|DatalinksLocked=T|DatabaseDatalinksLocked=T
|RECORD=46|OwnerIndex=384
|RECORD=48|OwnerIndex=384
|RECORD=41|OwnerIndex=386|IndexInSheet=-1|OwnerPartId=-1|Color=8388608|FontID=1|IsHidden=T|Text=2D|Name=Available Preview Images
|RECORD=1|LibReference=RES-2|ComponentDescription=Chip Resistor, 4.7 KOhm, +/- 1%, 0.1 W, -55 to 155 degC, 0603 (1608 Metric), RoHS, Tape and Reel RC0603FR-074K7L|PartCount=2|DisplayModeCount=1|IndexInSheet=38|OwnerPartId=-1|Location.X=1040|Location.Y=200|Orientation=1|CurrentPartId=1|LibraryPath=*|SourceLibraryName=Altium Content Vault|TargetFileName=*|AreaColor=11599871|Color=128|PartIDLocked=T|DesignItemId=CMP-2000-06942-1|AllPinCount=2
|RECORD=2|OwnerIndex=388|OwnerPartId=1|FormalType=1|Electrical=4|PinConglomerate=33|PinLength=10|Location.X=1040|Location.Y=220|Name=2|Designator=2|PinPropagationDelay=0.000000E+000
|RECORD=2|OwnerIndex=388|OwnerPartId=1|FormalType=1|Electrical=4|PinConglomerate=35|PinLength=10|Location.X=1040|Location.Y=200|Name=1|Designator=1|PinPropagationDelay=0.000000E+000
|RECORD=6|OwnerIndex=388|IsNotAccesible=T|IndexInSheet=2|OwnerPartId=1|LineWidth=1|Color=16711680|LocationCount=10|X1=1040|Y1=220|X2=1040|Y2=216|X3=1042|Y3=215|X4=1038|Y4=213|X5=1042|Y5=211|X6=1038|Y6=209|X7=1042|Y7=207|X8=1038|Y8=205|X9=1040|Y9=204|X10=1040|Y10=200
|RECORD=41|OwnerIndex=388|IndexInSheet=3|OwnerPartId=-1|Location.X=1037|Location.Y=232|Color=8388608|FontID=1|IsHidden=T|Text=0603|Name=Package Reference
|RECORD=41|OwnerIndex=388|IndexInSheet=4|OwnerPartId=-1|Location.X=1037|Location.Y=232|Color=8388608|FontID=1|IsHidden=T|Text=RC|Name=Series
|RECORD=41|OwnerIndex=388|IndexInSheet=5|OwnerPartId=-1|Location.X=1037|Location.Y=232|Color=8388608|FontID=1|IsHidden=T|Text=100mW|Name=Power Rating
|RECORD=41|OwnerIndex=388|IndexInSheet=6|OwnerPartId=-1|Location.X=1037|Location.Y=232|Color=8388608|FontID=1|IsHidden=T|Text=Yageo|Name=Manufacturer
|RECORD=41|OwnerIndex=388|IndexInSheet=7|OwnerPartId=-1|Location.X=1037|Location.Y=232|Color=8388608|FontID=1|IsHidden=T|Text=100PPM/C|Name=Temperature Coefficient
|RECORD=41|OwnerIndex=388|IndexInSheet=8|OwnerPartId=-1|Location.X=1037|Location.Y=232|Color=8388608|FontID=1|IsHidden=T|Text=4.7kOhms|Name=Resistance
|RECORD=41|OwnerIndex=388|IndexInSheet=9|OwnerPartId=-1|Location.X=1037|Location.Y=232|Color=8388608|FontID=1|IsHidden=T|Text=Rev. 7, 05/2017|Name=Datasheet Version
|RECORD=41|OwnerIndex=388|IndexInSheet=10|OwnerPartId=-1|Location.X=1037|Location.Y=232|Color=8388608|FontID=1|IsHidden=T|Text=Reel|Name=Packaging
|RECORD=41|OwnerIndex=388|IndexInSheet=11|OwnerPartId=-1|Location.X=1037|Location.Y=232|Color=8388608|FontID=1|IsHidden=T|Text=SMD/SMT|Name=Termination Style
|RECORD=41|OwnerIndex=388|IndexInSheet=12|OwnerPartId=-1|Location.X=1037|Location.Y=232|Color=8388608|FontID=7|IsHidden=T|Text=http://www.yageo.com/documents/recent/PYu-RC_Group_51_RoHS_L_7.pdf|Name=Datasheet URL
|RECORD=41|OwnerIndex=388|IndexInSheet=13|OwnerPartId=-1|Location.X=1037|Location.Y=232|Color=8388608|FontID=7|IsHidden=T|Text=http://www.yageo.com/|Name=Manufacturer URL
|RECORD=41|OwnerIndex=388|IndexInSheet=14|OwnerPartId=-1|Location.X=1037|Location.Y=232|Color=8388608|FontID=1|IsHidden=T|Text=2-Pin Surface Mount Device, Body 1.6 x 0.8 mm|Name=Package Description
|RECORD=41|OwnerIndex=388|IndexInSheet=15|OwnerPartId=-1|Location.X=1037|Location.Y=232|Color=8388608|FontID=1|IsHidden=T|Text=1608|Name=Case Code - mm
|RECORD=41|OwnerIndex=388|IndexInSheet=16|OwnerPartId=-1|Location.X=1037|Location.Y=232|Color=8388608|FontID=1|IsHidden=T|Text=50V|Name=Voltage Rating
|RECORD=41|OwnerIndex=388|IndexInSheet=17|OwnerPartId=-1|Location.X=1037|Location.Y=232|Color=8388608|FontID=1|IsHidden=T|Text=0603|Name=Case Code - in
|RECORD=41|OwnerIndex=388|IndexInSheet=18|OwnerPartId=-1|Location.X=1037|Location.Y=232|Color=8388608|FontID=1|IsHidden=T|Text=SurfaceMount|Name=Mounting Technology
|RECORD=41|OwnerIndex=388|IndexInSheet=19|OwnerPartId=-1|Location.X=1037|Location.Y=232|Color=8388608|FontID=1|IsHidden=T|Text=-55Cto+155C|Name=Operating Temperature Range
|RECORD=41|OwnerIndex=388|IndexInSheet=20|OwnerPartId=-1|Location.X=1037|Location.Y=232|Color=8388608|FontID=1|IsHidden=T|Text=1%|Name=Tolerance
|RECORD=41|OwnerIndex=388|IndexInSheet=21|OwnerPartId=-1|Location.X=1037|Location.Y=232|Color=8388608|FontID=1|IsHidden=T|Text=ThickFilmResistorsGeneralPurpose|Name=Product
|RECORD=34|OwnerIndex=388|IndexInSheet=-1|OwnerPartId=-1|Location.X=1043|Location.Y=211|Color=8388608|FontID=1|Text=R11|Name=Designator|ReadOnlyState=1
|RECORD=41|OwnerIndex=388|IndexInSheet=-1|OwnerPartId=-1|Location.X=1043|Location.Y=201|Color=8388608|FontID=1|Text=4.7K|Name=Comment
|RECORD=44|OwnerIndex=388
|RECORD=45|OwnerIndex=415|IndexInSheet=-1|Description=Chip Resistor, 2-Leads, Body 1.60x0.80mm, IPC High Density|UseComponentLibrary=T|ModelName=RESC1608X55X25LL10T15|ModelType=PCBLIB|DatafileCount=1|ModelDatafileEntity0=RESC1608X55X25LL10T15|ModelDatafileKind0=PCBLib|IsCurrent=T|DatalinksLocked=T|DatabaseDatalinksLocked=T
|RECORD=46|OwnerIndex=416
|RECORD=48|OwnerIndex=416
|RECORD=41|OwnerIndex=418|IndexInSheet=-1|OwnerPartId=-1|Color=8388608|FontID=1|IsHidden=T|Text=2D|Name=Available Preview Images
|RECORD=45|OwnerIndex=415|IndexInSheet=-1|Description=Chip Resistor, 2-Leads, Body 1.70x0.90mm, IPC Low Density|UseComponentLibrary=T|ModelName=RESC1608X55X25ML10T15|ModelType=PCBLIB|DatafileCount=1|ModelDatafileEntity0=RESC1608X55X25ML10T15|ModelDatafileKind0=PCBLib|DatalinksLocked=T|DatabaseDatalinksLocked=T
|RECORD=46|OwnerIndex=420
|RECORD=48|OwnerIndex=420
|RECORD=41|OwnerIndex=422|IndexInSheet=-1|OwnerPartId=-1|Color=8388608|FontID=1|IsHidden=T|Text=2D|Name=Available Preview Images
|RECORD=45|OwnerIndex=415|IndexInSheet=-1|Description=Chip Resistor, 2-Leads, Body 1.70x0.90mm, IPC Medium Density|UseComponentLibrary=T|ModelName=RESC1608X55X25NL10T15|ModelType=PCBLIB|DatafileCount=1|ModelDatafileEntity0=RESC1608X55X25NL10T15|ModelDatafileKind0=PCBLib|DatalinksLocked=T|DatabaseDatalinksLocked=T
|RECORD=46|OwnerIndex=424
|RECORD=48|OwnerIndex=424
|RECORD=41|OwnerIndex=426|IndexInSheet=-1|OwnerPartId=-1|Color=8388608|FontID=1|IsHidden=T|Text=2D|Name=Available Preview Images
|RECORD=1|LibReference=RES-2|ComponentDescription=Chip Resistor, 4.7 KOhm, +/- 1%, 0.1 W, -55 to 155 degC, 0603 (1608 Metric), RoHS, Tape and Reel RC0603FR-074K7L|PartCount=2|DisplayModeCount=1|IndexInSheet=39|OwnerPartId=-1|Location.X=1010|Location.Y=200|Orientation=1|CurrentPartId=1|LibraryPath=*|SourceLibraryName=Altium Content Vault|TargetFileName=*|AreaColor=11599871|Color=128|PartIDLocked=T|DesignItemId=CMP-2000-06942-1|AllPinCount=2
|RECORD=2|OwnerIndex=428|OwnerPartId=1|FormalType=1|Electrical=4|PinConglomerate=33|PinLength=10|Location.X=1010|Location.Y=220|Name=2|Designator=2|PinPropagationDelay=0.000000E+000
|RECORD=2|OwnerIndex=428|OwnerPartId=1|FormalType=1|Electrical=4|PinConglomerate=35|PinLength=10|Location.X=1010|Location.Y=200|Name=1|Designator=1|PinPropagationDelay=0.000000E+000
|RECORD=6|OwnerIndex=428|IsNotAccesible=T|IndexInSheet=2|OwnerPartId=1|LineWidth=1|Color=16711680|LocationCount=10|X1=1010|Y1=220|X2=1010|Y2=216|X3=1012|Y3=215|X4=1008|Y4=213|X5=1012|Y5=211|X6=1008|Y6=209|X7=1012|Y7=207|X8=1008|Y8=205|X9=1010|Y9=204|X10=1010|Y10=200
|RECORD=41|OwnerIndex=428|IndexInSheet=3|OwnerPartId=-1|Location.X=1007|Location.Y=232|Color=8388608|FontID=1|IsHidden=T|Text=0603|Name=Package Reference
|RECORD=41|OwnerIndex=428|IndexInSheet=4|OwnerPartId=-1|Location.X=1007|Location.Y=232|Color=8388608|FontID=1|IsHidden=T|Text=RC|Name=Series
|RECORD=41|OwnerIndex=428|IndexInSheet=5|OwnerPartId=-1|Location.X=1007|Location.Y=232|Color=8388608|FontID=1|IsHidden=T|Text=100mW|Name=Power Rating
|RECORD=41|OwnerIndex=428|IndexInSheet=6|OwnerPartId=-1|Location.X=1007|Location.Y=232|Color=8388608|FontID=1|IsHidden=T|Text=Yageo|Name=Manufacturer
|RECORD=41|OwnerIndex=428|IndexInSheet=7|OwnerPartId=-1|Location.X=1007|Location.Y=232|Color=8388608|FontID=1|IsHidden=T|Text=100PPM/C|Name=Temperature Coefficient
|RECORD=41|OwnerIndex=428|IndexInSheet=8|OwnerPartId=-1|Location.X=1007|Location.Y=232|Color=8388608|FontID=1|IsHidden=T|Text=4.7kOhms|Name=Resistance
|RECORD=41|OwnerIndex=428|IndexInSheet=9|OwnerPartId=-1|Location.X=1007|Location.Y=232|Color=8388608|FontID=1|IsHidden=T|Text=Rev. 7, 05/2017|Name=Datasheet Version
|RECORD=41|OwnerIndex=428|IndexInSheet=10|OwnerPartId=-1|Location.X=1007|Location.Y=232|Color=8388608|FontID=1|IsHidden=T|Text=Reel|Name=Packaging
|RECORD=41|OwnerIndex=428|IndexInSheet=11|OwnerPartId=-1|Location.X=1007|Location.Y=232|Color=8388608|FontID=1|IsHidden=T|Text=SMD/SMT|Name=Termination Style
|RECORD=41|OwnerIndex=428|IndexInSheet=12|OwnerPartId=-1|Location.X=1007|Location.Y=232|Color=8388608|FontID=7|IsHidden=T|Text=http://www.yageo.com/documents/recent/PYu-RC_Group_51_RoHS_L_7.pdf|Name=Datasheet URL
|RECORD=41|OwnerIndex=428|IndexInSheet=13|OwnerPartId=-1|Location.X=1007|Location.Y=232|Color=8388608|FontID=7|IsHidden=T|Text=http://www.yageo.com/|Name=Manufacturer URL
|RECORD=41|OwnerIndex=428|IndexInSheet=14|OwnerPartId=-1|Location.X=1007|Location.Y=232|Color=8388608|FontID=1|IsHidden=T|Text=2-Pin Surface Mount Device, Body 1.6 x 0.8 mm|Name=Package Description
|RECORD=41|OwnerIndex=428|IndexInSheet=15|OwnerPartId=-1|Location.X=1007|Location.Y=232|Color=8388608|FontID=1|IsHidden=T|Text=1608|Name=Case Code - mm
|RECORD=41|OwnerIndex=428|IndexInSheet=16|OwnerPartId=-1|Location.X=1007|Location.Y=232|Color=8388608|FontID=1|IsHidden=T|Text=50V|Name=Voltage Rating
|RECORD=41|OwnerIndex=428|IndexInSheet=17|OwnerPartId=-1|Location.X=1007|Location.Y=232|Color=8388608|FontID=1|IsHidden=T|Text=0603|Name=Case Code - in
|RECORD=41|OwnerIndex=428|IndexInSheet=18|OwnerPartId=-1|Location.X=1007|Location.Y=232|Color=8388608|FontID=1|IsHidden=T|Text=SurfaceMount|Name=Mounting Technology
|RECORD=41|OwnerIndex=428|IndexInSheet=19|OwnerPartId=-1|Location.X=1007|Location.Y=232|Color=8388608|FontID=1|IsHidden=T|Text=-55Cto+155C|Name=Operating Temperature Range
|RECORD=41|OwnerIndex=428|IndexInSheet=20|OwnerPartId=-1|Location.X=1007|Location.Y=232|Color=8388608|FontID=1|IsHidden=T|Text=1%|Name=Tolerance
|RECORD=41|OwnerIndex=428|IndexInSheet=21|OwnerPartId=-1|Location.X=1007|Location.Y=232|Color=8388608|FontID=1|IsHidden=T|Text=ThickFilmResistorsGeneralPurpose|Name=Product
|RECORD=34|OwnerIndex=428|IndexInSheet=-1|OwnerPartId=-1|Location.X=1013|Location.Y=211|Color=8388608|FontID=1|Text=R10|Name=Designator|ReadOnlyState=1
|RECORD=41|OwnerIndex=428|IndexInSheet=-1|OwnerPartId=-1|Location.X=1013|Location.Y=201|Color=8388608|FontID=1|Text=4.7K|Name=Comment
|RECORD=44|OwnerIndex=428
|RECORD=45|OwnerIndex=455|IndexInSheet=-1|Description=Chip Resistor, 2-Leads, Body 1.60x0.80mm, IPC High Density|UseComponentLibrary=T|ModelName=RESC1608X55X25LL10T15|ModelType=PCBLIB|DatafileCount=1|ModelDatafileEntity0=RESC1608X55X25LL10T15|ModelDatafileKind0=PCBLib|IsCurrent=T|DatalinksLocked=T|DatabaseDatalinksLocked=T
|RECORD=46|OwnerIndex=456
|RECORD=48|OwnerIndex=456
|RECORD=41|OwnerIndex=458|IndexInSheet=-1|OwnerPartId=-1|Color=8388608|FontID=1|IsHidden=T|Text=2D|Name=Available Preview Images
|RECORD=45|OwnerIndex=455|IndexInSheet=-1|Description=Chip Resistor, 2-Leads, Body 1.70x0.90mm, IPC Low Density|UseComponentLibrary=T|ModelName=RESC1608X55X25ML10T15|ModelType=PCBLIB|DatafileCount=1|ModelDatafileEntity0=RESC1608X55X25ML10T15|ModelDatafileKind0=PCBLib|DatalinksLocked=T|DatabaseDatalinksLocked=T
|RECORD=46|OwnerIndex=460
|RECORD=48|OwnerIndex=460
|RECORD=41|OwnerIndex=462|IndexInSheet=-1|OwnerPartId=-1|Color=8388608|FontID=1|IsHidden=T|Text=2D|Name=Available Preview Images
|RECORD=45|OwnerIndex=455|IndexInSheet=-1|Description=Chip Resistor, 2-Leads, Body 1.70x0.90mm, IPC Medium Density|UseComponentLibrary=T|ModelName=RESC1608X55X25NL10T15|ModelType=PCBLIB|DatafileCount=1|ModelDatafileEntity0=RESC1608X55X25NL10T15|ModelDatafileKind0=PCBLib|DatalinksLocked=T|DatabaseDatalinksLocked=T
|RECORD=46|OwnerIndex=464
|RECORD=48|OwnerIndex=464
|RECORD=41|OwnerIndex=466|IndexInSheet=-1|OwnerPartId=-1|Color=8388608|FontID=1|IsHidden=T|Text=2D|Name=Available Preview Images
|RECORD=1|LibReference=CAP|ComponentDescription=C0603X104K5RACAUTO|PartCount=2|DisplayModeCount=2|IndexInSheet=40|OwnerPartId=-1|Location.X=1070|Location.Y=200|Orientation=1|CurrentPartId=1|SourceLibraryName=Altium Content Vault|TargetFileName=*|AreaColor=11599871|Color=128|PartIDLocked=F|DesignItemId=CMP-2006-00003-1|AllPinCount=2
|RECORD=2|OwnerIndex=468|OwnerPartId=1|OwnerPartDisplayMode=1|FormalType=1|Electrical=4|PinConglomerate=35|PinLength=10|Location.X=1080|Location.Y=200|Name=1|Designator=1|PinPropagationDelay=0.000000E+000
|RECORD=2|OwnerIndex=468|OwnerPartId=1|OwnerPartDisplayMode=1|FormalType=1|Electrical=4|PinConglomerate=33|PinLength=10|Location.X=1080|Location.Y=210|Name=2|Designator=2|PinPropagationDelay=0.000000E+000
|RECORD=13|OwnerIndex=468|IsNotAccesible=T|IndexInSheet=2|OwnerPartId=1|OwnerPartDisplayMode=1|Location.X=1088|Location.Y=200|Corner.X=1072|Corner.Y=200|LineWidth=1|Color=16711680
|RECORD=13|OwnerIndex=468|IsNotAccesible=T|IndexInSheet=3|OwnerPartId=1|OwnerPartDisplayMode=1|Location.X=1080|Location.Y=204|Corner.X=1080|Corner.Y=210|LineWidth=1|Color=16711680
|RECORD=12|OwnerIndex=468|IsNotAccesible=T|IndexInSheet=4|OwnerPartId=1|OwnerPartDisplayMode=1|Location.X=1080|Location.Y=220|Radius=16|LineWidth=1|StartAngle=241.000|EndAngle=270.000|Color=16711680
|RECORD=12|OwnerIndex=468|IsNotAccesible=T|IndexInSheet=5|OwnerPartId=1|OwnerPartDisplayMode=1|Location.X=1080|Location.Y=220|Radius=16|LineWidth=1|StartAngle=270.000|EndAngle=299.000|Color=16711680
|RECORD=2|OwnerIndex=468|OwnerPartId=1|FormalType=1|Electrical=4|PinConglomerate=35|PinLength=10|Location.X=1080|Location.Y=200|Name=1|Designator=1|PinPropagationDelay=0.000000E+000
|RECORD=2|OwnerIndex=468|OwnerPartId=1|FormalType=1|Electrical=4|PinConglomerate=33|PinLength=10|Location.X=1080|Location.Y=210|Name=2|Designator=2|PinPropagationDelay=0.000000E+000
|RECORD=13|OwnerIndex=468|IsNotAccesible=T|IndexInSheet=8|OwnerPartId=1|Location.X=1072|Location.Y=207|Corner.X=1088|Corner.Y=207|LineWidth=1|Color=16711680
|RECORD=13|OwnerIndex=468|IsNotAccesible=T|IndexInSheet=9|OwnerPartId=1|Location.X=1088|Location.Y=203|Corner.X=1072|Corner.Y=203|LineWidth=1|Color=16711680
|RECORD=6|OwnerIndex=468|IsNotAccesible=T|IndexInSheet=10|OwnerPartId=1|LineWidth=1|Color=16711680|LocationCount=2|X1=1080|Y1=200|X2=1080|Y2=203
|RECORD=6|OwnerIndex=468|IsNotAccesible=T|IndexInSheet=11|OwnerPartId=1|LineWidth=1|Color=16711680|LocationCount=2|X1=1080|Y1=210|X2=1080|Y2=207
|RECORD=41|OwnerIndex=468|IndexInSheet=12|OwnerPartId=-1|Location.X=1071|Location.Y=222|Color=8388608|FontID=1|IsHidden=T|Text=Kemet|Name=Manufacturer
|RECORD=41|OwnerIndex=468|IndexInSheet=13|OwnerPartId=-1|Location.X=1071|Location.Y=222|Color=8388608|FontID=1|IsHidden=T|Text=C0603X104K5RACAUTO|Name=Part Number
|RECORD=34|OwnerIndex=468|IndexInSheet=-1|OwnerPartId=-1|Location.X=1089|Location.Y=201|Color=8388608|FontID=1|Text=C23|Name=Designator|ReadOnlyState=1
|RECORD=41|OwnerIndex=468|IndexInSheet=-1|OwnerPartId=-1|Location.X=1089|Location.Y=191|Color=8388608|FontID=1|Text=0.1uF|Name=Comment
|RECORD=44|OwnerIndex=468
|RECORD=45|OwnerIndex=489|IndexInSheet=-1|Description=Chip Capacitor, 2-Leads, Body 1.60x0.80mm, IPC Low Density|UseComponentLibrary=T|ModelName=CAPC1608X87X45ML20T05|ModelType=PCBLIB|DatafileCount=1|ModelDatafileEntity0=CAPC1608X87X45ML20T05|ModelDatafileKind0=PCBLib|IsCurrent=T|DatalinksLocked=T|DatabaseDatalinksLocked=T
|RECORD=46|OwnerIndex=490
|RECORD=48|OwnerIndex=490
|RECORD=41|OwnerIndex=492|IndexInSheet=-1|OwnerPartId=-1|Color=8388608|FontID=1|Text=2D|Name=Available Preview Images
|RECORD=45|OwnerIndex=489|IndexInSheet=-1|Description=Chip Capacitor, 2-Leads, Body 1.60x0.80mm, IPC High Density|UseComponentLibrary=T|ModelName=CAPC1608X87X45LL20T05|ModelType=PCBLIB|DatafileCount=1|ModelDatafileEntity0=CAPC1608X87X45LL20T05|ModelDatafileKind0=PCBLib|DatalinksLocked=T|DatabaseDatalinksLocked=T
|RECORD=46|OwnerIndex=494
|RECORD=48|OwnerIndex=494
|RECORD=41|OwnerIndex=496|IndexInSheet=-1|OwnerPartId=-1|Color=8388608|FontID=1|Text=2D|Name=Available Preview Images
|RECORD=45|OwnerIndex=489|IndexInSheet=-1|Description=Chip Capacitor, 2-Leads, Body 1.60x0.80mm, IPC Medium Density|UseComponentLibrary=T|ModelName=CAPC1608X87X45NL20T05|ModelType=PCBLIB|DatafileCount=1|ModelDatafileEntity0=CAPC1608X87X45NL20T05|ModelDatafileKind0=PCBLib|DatalinksLocked=T|DatabaseDatalinksLocked=T
|RECORD=46|OwnerIndex=498
|RECORD=48|OwnerIndex=498
|RECORD=41|OwnerIndex=500|IndexInSheet=-1|OwnerPartId=-1|Color=8388608|FontID=1|Text=2D|Name=Available Preview Images
|RECORD=17|IndexInSheet=41|OwnerPartId=-1|Style=4|ShowNetName=T|Location.X=1080|Location.Y=170|Orientation=3|Color=128|FontID=1|Text=GND
|RECORD=17|IndexInSheet=42|OwnerPartId=-1|Style=4|ShowNetName=T|Location.X=1040|Location.Y=170|Orientation=3|Color=128|FontID=1|Text=GND
|RECORD=17|IndexInSheet=43|OwnerPartId=-1|Style=4|ShowNetName=T|Location.X=1010|Location.Y=170|Orientation=3|Color=128|FontID=1|Text=GND
|RECORD=17|IndexInSheet=44|OwnerPartId=-1|ShowNetName=T|Location.X=1080|Location.Y=320|Orientation=1|Color=128|FontID=1|Text=+3.3V
|RECORD=17|IndexInSheet=45|OwnerPartId=-1|ShowNetName=T|Location.X=1280|Location.Y=280|Color=255|FontID=1|Text=MAC_PPS_IN1-|IsCrossSheetConnector=T
|RECORD=17|IndexInSheet=46|OwnerPartId=-1|ShowNetName=T|Location.X=1280|Location.Y=290|Color=255|FontID=1|Text=MAC_PPS_IN1+|IsCrossSheetConnector=T
|RECORD=17|IndexInSheet=47|OwnerPartId=-1|ShowNetName=T|Location.X=1280|Location.Y=250|Color=255|FontID=1|Text=MAC_PPS_IN0-|IsCrossSheetConnector=T
|RECORD=17|IndexInSheet=48|OwnerPartId=-1|ShowNetName=T|Location.X=1280|Location.Y=260|Color=255|FontID=1|Text=MAC_PPS_IN0+|IsCrossSheetConnector=T
|RECORD=17|IndexInSheet=49|OwnerPartId=-1|Style=4|ShowNetName=T|Location.X=1260|Location.Y=170|Orientation=3|Color=128|FontID=1|Text=GND
|RECORD=17|IndexInSheet=50|OwnerPartId=-1|ShowNetName=T|Location.X=590|Location.Y=840|Orientation=2|Color=255|FontID=1|Text=MAC_PPS_IN1-|IsCrossSheetConnector=T
|RECORD=17|IndexInSheet=51|OwnerPartId=-1|ShowNetName=T|Location.X=590|Location.Y=850|Orientation=2|Color=255|FontID=1|Text=MAC_PPS_IN1+|IsCrossSheetConnector=T
|RECORD=17|IndexInSheet=52|OwnerPartId=-1|ShowNetName=T|Location.X=590|Location.Y=820|Orientation=2|Color=255|FontID=1|Text=MAC_PPS_IN0-|IsCrossSheetConnector=T
|RECORD=17|IndexInSheet=53|OwnerPartId=-1|ShowNetName=T|Location.X=590|Location.Y=830|Orientation=2|Color=255|FontID=1|Text=MAC_PPS_IN0+|IsCrossSheetConnector=T
|RECORD=1|LibReference=RES|PartCount=2|DisplayModeCount=2|IndexInSheet=54|OwnerPartId=-1|Location.X=220|Location.Y=270|Orientation=1|CurrentPartId=1|SourceLibraryName=Altium Content Vault|TargetFileName=*|AreaColor=11599871|Color=128|PartIDLocked=F|DesignItemId=CMP-2000-03854-1|AllPinCount=2
|RECORD=2|OwnerIndex=515|OwnerPartId=1|OwnerPartDisplayMode=1|FormalType=1|Electrical=4|PinConglomerate=33|PinLength=10|Location.X=230|Location.Y=290|Name=2|Designator=2|PinPropagationDelay=0.000000E+000
|RECORD=2|OwnerIndex=515|OwnerPartId=1|OwnerPartDisplayMode=1|FormalType=1|Electrical=4|PinConglomerate=35|PinLength=10|Location.X=230|Location.Y=270|Name=1|Designator=1|PinPropagationDelay=0.000000E+000
|RECORD=14|OwnerIndex=515|IsNotAccesible=T|IndexInSheet=2|OwnerPartId=1|OwnerPartDisplayMode=1|Location.X=226|Location.Y=270|Corner.X=234|Corner.Y=290|LineWidth=1|Color=16711680|AreaColor=11599871
|RECORD=2|OwnerIndex=515|OwnerPartId=1|FormalType=1|Electrical=4|PinConglomerate=33|PinLength=10|Location.X=230|Location.Y=290|Name=2|Designator=2|PinPropagationDelay=0.000000E+000
|RECORD=2|OwnerIndex=515|OwnerPartId=1|FormalType=1|Electrical=4|PinConglomerate=35|PinLength=10|Location.X=230|Location.Y=270|Name=1|Designator=1|PinPropagationDelay=0.000000E+000
|RECORD=6|OwnerIndex=515|IsNotAccesible=T|IndexInSheet=5|OwnerPartId=1|LineWidth=1|Color=16711680|LocationCount=10|X1=230|Y1=290|X2=230|Y2=286|X3=232|Y3=285|X4=228|Y4=283|X5=232|Y5=281|X6=228|Y6=279|X7=232|Y7=277|X8=228|Y8=275|X9=230|Y9=274|X10=230|Y10=270
|RECORD=41|OwnerIndex=515|IndexInSheet=6|OwnerPartId=-1|Location.X=227|Location.Y=302|Color=8388608|FontID=1|IsHidden=T|Text=CRCW0603110RFKEA|Name=Part Number
|RECORD=41|OwnerIndex=515|IndexInSheet=7|OwnerPartId=-1|Location.X=227|Location.Y=302|Color=8388608|FontID=1|IsHidden=T|Text=Vishay Dale|Name=Manufacturer
|RECORD=34|OwnerIndex=515|IndexInSheet=-1|OwnerPartId=-1|Location.X=233|Location.Y=281|Color=8388608|FontID=1|Text=R12|Name=Designator|ReadOnlyState=1
|RECORD=41|OwnerIndex=515|IndexInSheet=-1|OwnerPartId=-1|Location.X=233|Location.Y=271|Color=8388608|FontID=1|Text=110R|Name=Comment
|RECORD=44|OwnerIndex=515
|RECORD=45|OwnerIndex=530|IndexInSheet=-1|Description=Chip Resistor, 2-Leads, Body 1.55x0.85mm, IPC Medium Density|UseComponentLibrary=T|ModelName=RESC1609X50X30NL10T20|ModelType=PCBLIB|DatafileCount=1|ModelDatafileEntity0=RESC1609X50X30NL10T20|ModelDatafileKind0=PCBLib|IsCurrent=T|DatalinksLocked=T|DatabaseDatalinksLocked=T
|RECORD=46|OwnerIndex=531
|RECORD=48|OwnerIndex=531
|RECORD=41|OwnerIndex=533|IndexInSheet=-1|OwnerPartId=-1|Color=8388608|FontID=1|IsHidden=T|Text=2D|Name=Available Preview Images
|RECORD=45|OwnerIndex=530|IndexInSheet=-1|Description=Chip Resistor, 2-Leads, Body 1.55x0.85mm, IPC High Density|UseComponentLibrary=T|ModelName=RESC1609X50X30LL10T20|ModelType=PCBLIB|DatafileCount=1|ModelDatafileEntity0=RESC1609X50X30LL10T20|ModelDatafileKind0=PCBLib|DatalinksLocked=T|DatabaseDatalinksLocked=T
|RECORD=46|OwnerIndex=535
|RECORD=48|OwnerIndex=535
|RECORD=41|OwnerIndex=537|IndexInSheet=-1|OwnerPartId=-1|Color=8388608|FontID=1|IsHidden=T|Text=2D|Name=Available Preview Images
|RECORD=45|OwnerIndex=530|IndexInSheet=-1|Description=Chip Resistor, 2-Leads, Body 1.55x0.85mm, IPC Low Density|UseComponentLibrary=T|ModelName=RESC1609X50X30ML10T20|ModelType=PCBLIB|DatafileCount=1|ModelDatafileEntity0=RESC1609X50X30ML10T20|ModelDatafileKind0=PCBLib|DatalinksLocked=T|DatabaseDatalinksLocked=T
|RECORD=46|OwnerIndex=539
|RECORD=48|OwnerIndex=539
|RECORD=41|OwnerIndex=541|IndexInSheet=-1|OwnerPartId=-1|Color=8388608|FontID=1|IsHidden=T|Text=2D|Name=Available Preview Images
|RECORD=1|LibReference=CAP|ComponentDescription=C0603X104K5RACAUTO|PartCount=2|DisplayModeCount=2|IndexInSheet=55|OwnerPartId=-1|Location.X=300|Location.Y=180|Orientation=3|CurrentPartId=1|SourceLibraryName=Altium Content Vault|TargetFileName=*|AreaColor=11599871|Color=128|PartIDLocked=F|DesignItemId=CMP-2006-00003-1|AllPinCount=2
|RECORD=2|OwnerIndex=543|OwnerPartId=1|OwnerPartDisplayMode=1|FormalType=1|Electrical=4|PinConglomerate=33|PinLength=10|Location.X=290|Location.Y=180|Name=1|Designator=1|PinPropagationDelay=0.000000E+000
|RECORD=2|OwnerIndex=543|OwnerPartId=1|OwnerPartDisplayMode=1|FormalType=1|Electrical=4|PinConglomerate=35|PinLength=10|Location.X=290|Location.Y=170|Name=2|Designator=2|PinPropagationDelay=0.000000E+000
|RECORD=13|OwnerIndex=543|IsNotAccesible=T|IndexInSheet=2|OwnerPartId=1|OwnerPartDisplayMode=1|Location.X=282|Location.Y=180|Corner.X=298|Corner.Y=180|LineWidth=1|Color=16711680
|RECORD=13|OwnerIndex=543|IsNotAccesible=T|IndexInSheet=3|OwnerPartId=1|OwnerPartDisplayMode=1|Location.X=290|Location.Y=176|Corner.X=290|Corner.Y=170|LineWidth=1|Color=16711680
|RECORD=12|OwnerIndex=543|IsNotAccesible=T|IndexInSheet=4|OwnerPartId=1|OwnerPartDisplayMode=1|Location.X=290|Location.Y=160|Radius=16|LineWidth=1|StartAngle=61.000|EndAngle=90.000|Color=16711680
|RECORD=12|OwnerIndex=543|IsNotAccesible=T|IndexInSheet=5|OwnerPartId=1|OwnerPartDisplayMode=1|Location.X=290|Location.Y=160|Radius=16|LineWidth=1|StartAngle=90.000|EndAngle=119.000|Color=16711680
|RECORD=2|OwnerIndex=543|OwnerPartId=1|FormalType=1|Electrical=4|PinConglomerate=33|PinLength=10|Location.X=290|Location.Y=180|Name=1|Designator=1|PinPropagationDelay=0.000000E+000
|RECORD=2|OwnerIndex=543|OwnerPartId=1|FormalType=1|Electrical=4|PinConglomerate=35|PinLength=10|Location.X=290|Location.Y=170|Name=2|Designator=2|PinPropagationDelay=0.000000E+000
|RECORD=13|OwnerIndex=543|IsNotAccesible=T|IndexInSheet=8|OwnerPartId=1|Location.X=298|Location.Y=173|Corner.X=282|Corner.Y=173|LineWidth=1|Color=16711680
|RECORD=13|OwnerIndex=543|IsNotAccesible=T|IndexInSheet=9|OwnerPartId=1|Location.X=282|Location.Y=177|Corner.X=298|Corner.Y=177|LineWidth=1|Color=16711680
|RECORD=6|OwnerIndex=543|IsNotAccesible=T|IndexInSheet=10|OwnerPartId=1|LineWidth=1|Color=16711680|LocationCount=2|X1=290|Y1=180|X2=290|Y2=177
|RECORD=6|OwnerIndex=543|IsNotAccesible=T|IndexInSheet=11|OwnerPartId=1|LineWidth=1|Color=16711680|LocationCount=2|X1=290|Y1=170|X2=290|Y2=173
|RECORD=41|OwnerIndex=543|IndexInSheet=12|OwnerPartId=-1|Location.X=281|Location.Y=192|Color=8388608|FontID=1|IsHidden=T|Text=Kemet|Name=Manufacturer
|RECORD=41|OwnerIndex=543|IndexInSheet=13|OwnerPartId=-1|Location.X=281|Location.Y=192|Color=8388608|FontID=1|IsHidden=T|Text=C0603X104K5RACAUTO|Name=Part Number
|RECORD=34|OwnerIndex=543|IndexInSheet=-1|OwnerPartId=-1|Location.X=299|Location.Y=167|Color=8388608|FontID=1|Text=C24|Name=Designator|ReadOnlyState=1
|RECORD=41|OwnerIndex=543|IndexInSheet=-1|OwnerPartId=-1|Location.X=299|Location.Y=153|Color=8388608|FontID=1|Text=0.1uF|Name=Comment
|RECORD=44|OwnerIndex=543
|RECORD=45|OwnerIndex=564|IndexInSheet=-1|Description=Chip Capacitor, 2-Leads, Body 1.60x0.80mm, IPC Low Density|UseComponentLibrary=T|ModelName=CAPC1608X87X45ML20T05|ModelType=PCBLIB|DatafileCount=1|ModelDatafileEntity0=CAPC1608X87X45ML20T05|ModelDatafileKind0=PCBLib|IsCurrent=T|DatalinksLocked=T|DatabaseDatalinksLocked=T
|RECORD=46|OwnerIndex=565
|RECORD=48|OwnerIndex=565
|RECORD=41|OwnerIndex=567|IndexInSheet=-1|OwnerPartId=-1|Color=8388608|FontID=1|Text=2D|Name=Available Preview Images
|RECORD=45|OwnerIndex=564|IndexInSheet=-1|Description=Chip Capacitor, 2-Leads, Body 1.60x0.80mm, IPC High Density|UseComponentLibrary=T|ModelName=CAPC1608X87X45LL20T05|ModelType=PCBLIB|DatafileCount=1|ModelDatafileEntity0=CAPC1608X87X45LL20T05|ModelDatafileKind0=PCBLib|DatalinksLocked=T|DatabaseDatalinksLocked=T
|RECORD=46|OwnerIndex=569
|RECORD=48|OwnerIndex=569
|RECORD=41|OwnerIndex=571|IndexInSheet=-1|OwnerPartId=-1|Color=8388608|FontID=1|Text=2D|Name=Available Preview Images
|RECORD=45|OwnerIndex=564|IndexInSheet=-1|Description=Chip Capacitor, 2-Leads, Body 1.60x0.80mm, IPC Medium Density|UseComponentLibrary=T|ModelName=CAPC1608X87X45NL20T05|ModelType=PCBLIB|DatafileCount=1|ModelDatafileEntity0=CAPC1608X87X45NL20T05|ModelDatafileKind0=PCBLib|DatalinksLocked=T|DatabaseDatalinksLocked=T
|RECORD=46|OwnerIndex=573
|RECORD=48|OwnerIndex=573
|RECORD=41|OwnerIndex=575|IndexInSheet=-1|OwnerPartId=-1|Color=8388608|FontID=1|Text=2D|Name=Available Preview Images
|RECORD=17|IndexInSheet=56|OwnerPartId=-1|ShowNetName=T|Location.X=290|Location.Y=330|Orientation=1|Color=128|FontID=1|Text=+3.3V
|RECORD=17|IndexInSheet=57|OwnerPartId=-1|Style=4|ShowNetName=T|Location.X=290|Location.Y=130|Orientation=3|Color=128|FontID=1|Text=GND
|RECORD=17|IndexInSheet=58|OwnerPartId=-1|Style=4|ShowNetName=T|Location.X=480|Location.Y=130|Orientation=3|Color=128|FontID=1|Text=GND
|RECORD=22|IndexInSheet=59|OwnerPartId=-1|Location.X=320|Location.Y=240|Color=255|Orientation=1|Symbol=Thin Cross|IsActive=T|SuppressAll=T
|RECORD=22|IndexInSheet=60|OwnerPartId=-1|Location.X=320|Location.Y=230|Color=255|Orientation=1|Symbol=Thin Cross|IsActive=T|SuppressAll=T
|RECORD=22|IndexInSheet=61|OwnerPartId=-1|Location.X=440|Location.Y=240|Color=255|Orientation=1|Symbol=Thin Cross|IsActive=T|SuppressAll=T
|RECORD=1|LibReference=RES-2|ComponentDescription=General Purpose Chip Resistor, 49.9 Ohm, +/- 1%, -55 to 155 degC, 0603 (1608 Metric), RoHS, Tape and Reel|PartCount=2|DisplayModeCount=1|IndexInSheet=62|OwnerPartId=-1|Location.X=470|Location.Y=270|CurrentPartId=1|LibraryPath=*|SourceLibraryName=Altium Content Vault|TargetFileName=*|AreaColor=11599871|Color=128|PartIDLocked=T|DesignItemId=CMP-1659-00036-1|AllPinCount=2
|RECORD=2|OwnerIndex=583|OwnerPartId=1|FormalType=1|Electrical=4|PinConglomerate=32|PinLength=10|Location.X=490|Location.Y=270|Name=2|Designator=2|PinPropagationDelay=0.000000E+000
|RECORD=2|OwnerIndex=583|OwnerPartId=1|FormalType=1|Electrical=4|PinConglomerate=34|PinLength=10|Location.X=470|Location.Y=270|Name=1|Designator=1|PinPropagationDelay=0.000000E+000
|RECORD=6|OwnerIndex=583|IsNotAccesible=T|IndexInSheet=2|OwnerPartId=1|LineWidth=1|Color=16711680|LocationCount=10|X1=490|Y1=270|X2=486|Y2=270|X3=485|Y3=268|X4=483|Y4=272|X5=481|Y5=268|X6=479|Y6=272|X7=477|Y7=268|X8=475|Y8=272|X9=474|Y9=270|X10=470|Y10=270
|RECORD=41|OwnerIndex=583|IndexInSheet=3|OwnerPartId=-1|Location.X=458|Location.Y=285|Color=8388608|FontID=1|IsHidden=T|Text=0603|Name=PackageReference
|RECORD=41|OwnerIndex=583|IndexInSheet=4|OwnerPartId=-1|Location.X=458|Location.Y=285|Color=8388608|FontID=1|IsHidden=T|Text=Tray|Name=Packaging
|RECORD=41|OwnerIndex=583|IndexInSheet=5|OwnerPartId=-1|Location.X=458|Location.Y=285|Color=8388608|FontID=1|IsHidden=T|Text=Datasheet|Name=ComponentLink2Description
|RECORD=41|OwnerIndex=583|IndexInSheet=6|OwnerPartId=-1|Location.X=458|Location.Y=285|Color=8388608|FontID=1|IsHidden=T|Text=Manufacturer URL|Name=ComponentLink1Description
|RECORD=41|OwnerIndex=583|IndexInSheet=7|OwnerPartId=-1|Location.X=458|Location.Y=285|Color=8388608|FontID=7|IsHidden=T|Text=https://datasheet.ciiva.com/11808/0900766b80f96399-11808223.pdf|Name=ComponentLink2URL
|RECORD=41|OwnerIndex=583|IndexInSheet=8|OwnerPartId=-1|Location.X=458|Location.Y=285|Color=8388608|FontID=1|IsHidden=T|Text=true|Name=RoHSCompliant
|RECORD=41|OwnerIndex=583|IndexInSheet=9|OwnerPartId=-1|Location.X=458|Location.Y=285|Color=8388608|FontID=1|IsHidden=T|Text=85 degC|Name=Max Operating Temperature
|RECORD=41|OwnerIndex=583|IndexInSheet=10|OwnerPartId=-1|Location.X=458|Location.Y=285|Color=8388608|FontID=1|IsHidden=T|Text=3.63 V|Name=Max Supply Voltage
|RECORD=41|OwnerIndex=583|IndexInSheet=11|OwnerPartId=-1|Location.X=458|Location.Y=285|Color=8388608|FontID=7|IsHidden=T|Text=http://www.yageo.com/|Name=ComponentLink1URL
|RECORD=41|OwnerIndex=583|IndexInSheet=12|OwnerPartId=-1|Location.X=458|Location.Y=285|Color=8388608|FontID=1|IsHidden=T|Text=2-Pin Surface Mount Device, Body 1.6 x 0.8 mm|Name=PackageDescription
|RECORD=41|OwnerIndex=583|IndexInSheet=13|OwnerPartId=-1|Location.X=458|Location.Y=285|Color=8388608|FontID=1|IsHidden=T|Text=LQFP|Name=Case\Package
|RECORD=41|OwnerIndex=583|IndexInSheet=14|OwnerPartId=-1|Location.X=458|Location.Y=285|Color=8388608|FontID=1|IsHidden=T|Text=Rev. 4, 04/2009|Name=DatasheetVersion
|RECORD=41|OwnerIndex=583|IndexInSheet=15|OwnerPartId=-1|Location.X=458|Location.Y=285|Color=8388608|FontID=1|IsHidden=T|Text=-40 degC|Name=Min Operating Temperature
|RECORD=41|OwnerIndex=583|IndexInSheet=16|OwnerPartId=-1|Location.X=458|Location.Y=285|Color=8388608|FontID=1|IsHidden=T|Text=SPI|Name=Interface
|RECORD=41|OwnerIndex=583|IndexInSheet=17|OwnerPartId=-1|Location.X=458|Location.Y=285|Color=8388608|FontID=1|IsHidden=T|Text=250|Name=Package Quantity
|RECORD=41|OwnerIndex=583|IndexInSheet=18|OwnerPartId=-1|Location.X=458|Location.Y=285|Color=8388608|FontID=1|IsHidden=T|Text=2.97 V|Name=Min Supply Voltage
|RECORD=41|OwnerIndex=583|IndexInSheet=19|OwnerPartId=-1|Location.X=458|Location.Y=285|Color=8388608|FontID=1|IsHidden=T|Text=48|Name=Pins
|RECORD=34|OwnerIndex=583|IndexInSheet=-1|OwnerPartId=-1|Location.X=469|Location.Y=273|Color=8388608|FontID=1|Text=R13|Name=Designator|ReadOnlyState=1
|RECORD=41|OwnerIndex=583|IndexInSheet=-1|OwnerPartId=-1|Location.X=469|Location.Y=257|Color=8388608|FontID=1|Text=49.9R|Name=Comment
|RECORD=44|OwnerIndex=583
|RECORD=45|OwnerIndex=608|IndexInSheet=-1|Description=Chip Resistor, 2-Leads, Body 1.70x0.90mm, IPC Medium Density|UseComponentLibrary=T|ModelName=RESC1608X55X25NL10T15|ModelType=PCBLIB|DatafileCount=1|ModelDatafileEntity0=RESC1608X55X25NL10T15|ModelDatafileKind0=PCBLib|IsCurrent=T|DatalinksLocked=T|DatabaseDatalinksLocked=T
|RECORD=46|OwnerIndex=609
|RECORD=48|OwnerIndex=609
|RECORD=41|OwnerIndex=611|IndexInSheet=-1|OwnerPartId=-1|Color=8388608|FontID=1|IsHidden=T|Text=2D|Name=Available Preview Images
|RECORD=45|OwnerIndex=608|IndexInSheet=-1|Description=Chip Resistor, 2-Leads, Body 1.70x0.90mm, IPC Low Density|UseComponentLibrary=T|ModelName=RESC1608X55X25ML10T15|ModelType=PCBLIB|DatafileCount=1|ModelDatafileEntity0=RESC1608X55X25ML10T15|ModelDatafileKind0=PCBLib|DatalinksLocked=T|DatabaseDatalinksLocked=T
|RECORD=46|OwnerIndex=613
|RECORD=48|OwnerIndex=613
|RECORD=41|OwnerIndex=615|IndexInSheet=-1|OwnerPartId=-1|Color=8388608|FontID=1|IsHidden=T|Text=2D|Name=Available Preview Images
|RECORD=45|OwnerIndex=608|IndexInSheet=-1|Description=Chip Resistor, 2-Leads, Body 1.70x0.90mm, IPC High Density|UseComponentLibrary=T|ModelName=RESC1608X55X25LL10T15|ModelType=PCBLIB|DatafileCount=1|ModelDatafileEntity0=RESC1608X55X25LL10T15|ModelDatafileKind0=PCBLib|DatalinksLocked=T|DatabaseDatalinksLocked=T
|RECORD=46|OwnerIndex=617
|RECORD=48|OwnerIndex=617
|RECORD=41|OwnerIndex=619|IndexInSheet=-1|OwnerPartId=-1|Color=8388608|FontID=1|IsHidden=T|Text=2D|Name=Available Preview Images
|RECORD=17|IndexInSheet=63|OwnerPartId=-1|ShowNetName=T|Location.X=580|Location.Y=270|Color=255|FontID=1|Text=FPGA_MAC_PPS_OUT-|IsCrossSheetConnector=T
|RECORD=17|IndexInSheet=64|OwnerPartId=-1|ShowNetName=T|Location.X=1210|Location.Y=810|Color=255|FontID=1|Text=MAC_PPS_OUT+|IsCrossSheetConnector=T
|RECORD=17|IndexInSheet=65|OwnerPartId=-1|ShowNetName=T|Location.X=1210|Location.Y=800|Color=255|FontID=1|Text=MAC_PPS_OUT-|IsCrossSheetConnector=T
|RECORD=17|IndexInSheet=66|OwnerPartId=-1|ShowNetName=T|Location.X=970|Location.Y=290|Orientation=2|Color=255|FontID=1|Text=FPGA_MAC_PPS_IN1-|IsCrossSheetConnector=T
|RECORD=41|IndexInSheet=67|OwnerPartId=-1|Color=8388608|FontID=1|IsHidden=T|Text=*|Name=CurrentTime|ReadOnlyState=1
|RECORD=41|IndexInSheet=68|OwnerPartId=-1|Color=8388608|FontID=1|IsHidden=T|Text=*|Name=CurrentDate|ReadOnlyState=1
|RECORD=41|IndexInSheet=69|OwnerPartId=-1|Color=8388608|FontID=1|IsHidden=T|Text=*|Name=Time|ReadOnlyState=1
|RECORD=41|IndexInSheet=70|OwnerPartId=-1|Color=8388608|FontID=1|IsHidden=T|Text=*|Name=Date|ReadOnlyState=1
|RECORD=41|IndexInSheet=71|OwnerPartId=-1|Color=8388608|FontID=1|IsHidden=T|Text=*|Name=DocumentFullPathAndName|ReadOnlyState=1
|RECORD=41|IndexInSheet=72|OwnerPartId=-1|Color=8388608|FontID=1|IsHidden=T|Text=*|Name=DocumentName|ReadOnlyState=1
|RECORD=41|IndexInSheet=73|OwnerPartId=-1|Color=8388608|FontID=1|IsHidden=T|Text=*|Name=ModifiedDate|ReadOnlyState=1
|RECORD=41|IndexInSheet=74|OwnerPartId=-1|Color=8388608|FontID=1|IsHidden=T|Text=*|Name=ApprovedBy|ReadOnlyState=1
|RECORD=41|IndexInSheet=75|OwnerPartId=-1|Color=8388608|FontID=1|IsHidden=T|Text=*|Name=CheckedBy|ReadOnlyState=1
|RECORD=41|IndexInSheet=76|OwnerPartId=-1|Color=8388608|FontID=1|IsHidden=T|Text=*|Name=Author|ReadOnlyState=1
|RECORD=41|IndexInSheet=77|OwnerPartId=-1|Color=8388608|FontID=1|IsHidden=T|Text=*|Name=CompanyName|ReadOnlyState=1
|RECORD=41|IndexInSheet=78|OwnerPartId=-1|Color=8388608|FontID=1|IsHidden=T|Text=*|Name=DrawnBy|ReadOnlyState=1
|RECORD=41|IndexInSheet=79|OwnerPartId=-1|Color=8388608|FontID=1|IsHidden=T|Text=*|Name=Engineer|ReadOnlyState=1
|RECORD=41|IndexInSheet=80|OwnerPartId=-1|Color=8388608|FontID=1|IsHidden=T|Text=*|Name=Organization|ReadOnlyState=1
|RECORD=41|IndexInSheet=81|OwnerPartId=-1|Color=8388608|FontID=1|IsHidden=T|Text=*|Name=Address1|ReadOnlyState=1
|RECORD=41|IndexInSheet=82|OwnerPartId=-1|Color=8388608|FontID=1|IsHidden=T|Text=*|Name=Address2|ReadOnlyState=1
|RECORD=41|IndexInSheet=83|OwnerPartId=-1|Color=8388608|FontID=1|IsHidden=T|Text=*|Name=Address3|ReadOnlyState=1
|RECORD=41|IndexInSheet=84|OwnerPartId=-1|Color=8388608|FontID=1|IsHidden=T|Text=*|Name=Address4|ReadOnlyState=1
|RECORD=41|IndexInSheet=85|OwnerPartId=-1|Color=8388608|FontID=1|IsHidden=T|Text=*|Name=Title|ReadOnlyState=1
|RECORD=41|IndexInSheet=86|OwnerPartId=-1|Color=8388608|FontID=1|IsHidden=T|Text=*|Name=DocumentNumber|ReadOnlyState=1
|RECORD=41|IndexInSheet=87|OwnerPartId=-1|Color=8388608|FontID=1|IsHidden=T|Text=*|Name=Revision|ReadOnlyState=1
|RECORD=41|IndexInSheet=88|OwnerPartId=-1|Color=8388608|FontID=1|IsHidden=T|Text=*|Name=SheetNumber|ReadOnlyState=1
|RECORD=41|IndexInSheet=89|OwnerPartId=-1|Color=8388608|FontID=1|IsHidden=T|Text=*|Name=SheetTotal|ReadOnlyState=1
|RECORD=41|IndexInSheet=90|OwnerPartId=-1|Color=8388608|FontID=1|IsHidden=T|Text=*|Name=Rule|ReadOnlyState=1
|RECORD=41|IndexInSheet=91|OwnerPartId=-1|Color=8388608|FontID=1|IsHidden=T|Text=*|Name=ImagePath|ReadOnlyState=1
|RECORD=41|IndexInSheet=92|OwnerPartId=-1|Color=8388608|FontID=1|IsHidden=T|Text=*|Name=ProjectName|ReadOnlyState=1
|RECORD=41|IndexInSheet=93|OwnerPartId=-1|Color=8388608|FontID=1|IsHidden=T|Text=*|Name=Application_BuildNumber|ReadOnlyState=1
|RECORD=1|LibReference=RES-2|ComponentDescription=General Purpose Chip Resistor, 49.9 Ohm, +/- 1%, -55 to 155 degC, 0603 (1608 Metric), RoHS, Tape and Reel|PartCount=2|DisplayModeCount=1|IndexInSheet=94|OwnerPartId=-1|Location.X=470|Location.Y=320|CurrentPartId=1|LibraryPath=*|SourceLibraryName=Altium Content Vault|TargetFileName=*|AreaColor=11599871|Color=128|PartIDLocked=T|DesignItemId=CMP-1659-00036-1|AllPinCount=2|ComponentKindVersion2=5
|RECORD=2|OwnerIndex=652|OwnerPartId=1|FormalType=1|Electrical=4|PinConglomerate=32|PinLength=10|Location.X=490|Location.Y=320|Name=2|Designator=2|PinPropagationDelay=0.000000E+000
|RECORD=2|OwnerIndex=652|OwnerPartId=1|FormalType=1|Electrical=4|PinConglomerate=34|PinLength=10|Location.X=470|Location.Y=320|Name=1|Designator=1|PinPropagationDelay=0.000000E+000
|RECORD=6|OwnerIndex=652|IsNotAccesible=T|IndexInSheet=2|OwnerPartId=1|LineWidth=1|Color=16711680|LocationCount=10|X1=490|Y1=320|X2=486|Y2=320|X3=485|Y3=318|X4=483|Y4=322|X5=481|Y5=318|X6=479|Y6=322|X7=477|Y7=318|X8=475|Y8=322|X9=474|Y9=320|X10=470|Y10=320
|RECORD=41|OwnerIndex=652|IndexInSheet=3|OwnerPartId=-1|Location.X=458|Location.Y=335|Color=8388608|FontID=1|IsHidden=T|Text=0603|Name=PackageReference
|RECORD=41|OwnerIndex=652|IndexInSheet=4|OwnerPartId=-1|Location.X=458|Location.Y=335|Color=8388608|FontID=1|IsHidden=T|Text=Tray|Name=Packaging
|RECORD=41|OwnerIndex=652|IndexInSheet=5|OwnerPartId=-1|Location.X=458|Location.Y=335|Color=8388608|FontID=1|IsHidden=T|Text=Datasheet|Name=ComponentLink2Description
|RECORD=41|OwnerIndex=652|IndexInSheet=6|OwnerPartId=-1|Location.X=458|Location.Y=335|Color=8388608|FontID=1|IsHidden=T|Text=Manufacturer URL|Name=ComponentLink1Description
|RECORD=41|OwnerIndex=652|IndexInSheet=7|OwnerPartId=-1|Location.X=458|Location.Y=335|Color=8388608|FontID=7|IsHidden=T|Text=https://datasheet.ciiva.com/11808/0900766b80f96399-11808223.pdf|Name=ComponentLink2URL
|RECORD=41|OwnerIndex=652|IndexInSheet=8|OwnerPartId=-1|Location.X=458|Location.Y=335|Color=8388608|FontID=1|IsHidden=T|Text=true|Name=RoHSCompliant
|RECORD=41|OwnerIndex=652|IndexInSheet=9|OwnerPartId=-1|Location.X=458|Location.Y=335|Color=8388608|FontID=1|IsHidden=T|Text=85 degC|Name=Max Operating Temperature
|RECORD=41|OwnerIndex=652|IndexInSheet=10|OwnerPartId=-1|Location.X=458|Location.Y=335|Color=8388608|FontID=1|IsHidden=T|Text=3.63 V|Name=Max Supply Voltage
|RECORD=41|OwnerIndex=652|IndexInSheet=11|OwnerPartId=-1|Location.X=458|Location.Y=335|Color=8388608|FontID=7|IsHidden=T|Text=http://www.yageo.com/|Name=ComponentLink1URL
|RECORD=41|OwnerIndex=652|IndexInSheet=12|OwnerPartId=-1|Location.X=458|Location.Y=335|Color=8388608|FontID=1|IsHidden=T|Text=2-Pin Surface Mount Device, Body 1.6 x 0.8 mm|Name=PackageDescription
|RECORD=41|OwnerIndex=652|IndexInSheet=13|OwnerPartId=-1|Location.X=458|Location.Y=335|Color=8388608|FontID=1|IsHidden=T|Text=LQFP|Name=Case\Package
|RECORD=41|OwnerIndex=652|IndexInSheet=14|OwnerPartId=-1|Location.X=458|Location.Y=335|Color=8388608|FontID=1|IsHidden=T|Text=Rev. 4, 04/2009|Name=DatasheetVersion
|RECORD=41|OwnerIndex=652|IndexInSheet=15|OwnerPartId=-1|Location.X=458|Location.Y=335|Color=8388608|FontID=1|IsHidden=T|Text=-40 degC|Name=Min Operating Temperature
|RECORD=41|OwnerIndex=652|IndexInSheet=16|OwnerPartId=-1|Location.X=458|Location.Y=335|Color=8388608|FontID=1|IsHidden=T|Text=SPI|Name=Interface
|RECORD=41|OwnerIndex=652|IndexInSheet=17|OwnerPartId=-1|Location.X=458|Location.Y=335|Color=8388608|FontID=1|IsHidden=T|Text=250|Name=Package Quantity
|RECORD=41|OwnerIndex=652|IndexInSheet=18|OwnerPartId=-1|Location.X=458|Location.Y=335|Color=8388608|FontID=1|IsHidden=T|Text=2.97 V|Name=Min Supply Voltage
|RECORD=41|OwnerIndex=652|IndexInSheet=19|OwnerPartId=-1|Location.X=458|Location.Y=335|Color=8388608|FontID=1|IsHidden=T|Text=48|Name=Pins
|RECORD=34|OwnerIndex=652|IndexInSheet=-1|OwnerPartId=-1|Location.X=469|Location.Y=323|Color=8388608|FontID=1|Text=R43|Name=Designator|ReadOnlyState=1
|RECORD=41|OwnerIndex=652|IndexInSheet=-1|OwnerPartId=-1|Location.X=469|Location.Y=307|Color=8388608|FontID=1|Text=DNI_49.9R|Name=Comment
|RECORD=44|OwnerIndex=652
|RECORD=45|OwnerIndex=677|IndexInSheet=-1|Description=Chip Resistor, 2-Leads, Body 1.70x0.90mm, IPC Medium Density|UseComponentLibrary=T|ModelName=RESC1608X55X25NL10T15|ModelType=PCBLIB|DatafileCount=1|ModelDatafileEntity0=RESC1608X55X25NL10T15|ModelDatafileKind0=PCBLib|IsCurrent=T|DatalinksLocked=T|DatabaseDatalinksLocked=T
|RECORD=46|OwnerIndex=678
|RECORD=48|OwnerIndex=678
|RECORD=41|OwnerIndex=680|IndexInSheet=-1|OwnerPartId=-1|Color=8388608|FontID=1|IsHidden=T|Text=2D|Name=Available Preview Images
|RECORD=45|OwnerIndex=677|IndexInSheet=-1|Description=Chip Resistor, 2-Leads, Body 1.70x0.90mm, IPC Low Density|UseComponentLibrary=T|ModelName=RESC1608X55X25ML10T15|ModelType=PCBLIB|DatafileCount=1|ModelDatafileEntity0=RESC1608X55X25ML10T15|ModelDatafileKind0=PCBLib|DatalinksLocked=T|DatabaseDatalinksLocked=T
|RECORD=46|OwnerIndex=682
|RECORD=48|OwnerIndex=682
|RECORD=41|OwnerIndex=684|IndexInSheet=-1|OwnerPartId=-1|Color=8388608|FontID=1|IsHidden=T|Text=2D|Name=Available Preview Images
|RECORD=45|OwnerIndex=677|IndexInSheet=-1|Description=Chip Resistor, 2-Leads, Body 1.70x0.90mm, IPC High Density|UseComponentLibrary=T|ModelName=RESC1608X55X25LL10T15|ModelType=PCBLIB|DatafileCount=1|ModelDatafileEntity0=RESC1608X55X25LL10T15|ModelDatafileKind0=PCBLib|DatalinksLocked=T|DatabaseDatalinksLocked=T
|RECORD=46|OwnerIndex=686
|RECORD=48|OwnerIndex=686
|RECORD=41|OwnerIndex=688|IndexInSheet=-1|OwnerPartId=-1|Color=8388608|FontID=1|IsHidden=T|Text=2D|Name=Available Preview Images
|RECORD=17|IndexInSheet=95|OwnerPartId=-1|ShowNetName=T|Location.X=1040|Location.Y=940|Color=255|FontID=1|Text=MAC_PPS_IN|IsCrossSheetConnector=T
|RECORD=17|IndexInSheet=96|OwnerPartId=-1|Style=1|ShowNetName=T|Location.X=1040|Location.Y=930|Color=255|FontID=1|Text=MAC_PPS_OUT|IsCrossSheetConnector=T
|RECORD=17|IndexInSheet=97|OwnerPartId=-1|ShowNetName=T|Location.X=430|Location.Y=320|Orientation=2|Color=255|FontID=1|Text=MAC_PPS_OUT|IsCrossSheetConnector=T
|RECORD=1|LibReference=RES-2|ComponentDescription=General Purpose Chip Resistor, 49.9 Ohm, +/- 1%, -55 to 155 degC, 0603 (1608 Metric), RoHS, Tape and Reel|PartCount=2|DisplayModeCount=1|IndexInSheet=98|OwnerPartId=-1|Location.X=1010|Location.Y=360|CurrentPartId=1|LibraryPath=*|SourceLibraryName=Altium Content Vault|TargetFileName=*|AreaColor=11599871|Color=128|PartIDLocked=T|DesignItemId=CMP-1659-00036-1|AllPinCount=2|ComponentKindVersion2=5
|RECORD=2|OwnerIndex=693|OwnerPartId=1|FormalType=1|Electrical=4|PinConglomerate=32|PinLength=10|Location.X=1030|Location.Y=360|Name=2|Designator=2|PinPropagationDelay=0.000000E+000
|RECORD=2|OwnerIndex=693|OwnerPartId=1|FormalType=1|Electrical=4|PinConglomerate=34|PinLength=10|Location.X=1010|Location.Y=360|Name=1|Designator=1|PinPropagationDelay=0.000000E+000
|RECORD=6|OwnerIndex=693|IsNotAccesible=T|IndexInSheet=2|OwnerPartId=1|LineWidth=1|Color=16711680|LocationCount=10|X1=1030|Y1=360|X2=1026|Y2=360|X3=1025|Y3=358|X4=1023|Y4=362|X5=1021|Y5=358|X6=1019|Y6=362|X7=1017|Y7=358|X8=1015|Y8=362|X9=1014|Y9=360|X10=1010|Y10=360
|RECORD=41|OwnerIndex=693|IndexInSheet=3|OwnerPartId=-1|Location.X=998|Location.Y=375|Color=8388608|FontID=1|IsHidden=T|Text=0603|Name=PackageReference
|RECORD=41|OwnerIndex=693|IndexInSheet=4|OwnerPartId=-1|Location.X=998|Location.Y=375|Color=8388608|FontID=1|IsHidden=T|Text=Tray|Name=Packaging
|RECORD=41|OwnerIndex=693|IndexInSheet=5|OwnerPartId=-1|Location.X=998|Location.Y=375|Color=8388608|FontID=1|IsHidden=T|Text=Datasheet|Name=ComponentLink2Description
|RECORD=41|OwnerIndex=693|IndexInSheet=6|OwnerPartId=-1|Location.X=998|Location.Y=375|Color=8388608|FontID=1|IsHidden=T|Text=Manufacturer URL|Name=ComponentLink1Description
|RECORD=41|OwnerIndex=693|IndexInSheet=7|OwnerPartId=-1|Location.X=998|Location.Y=375|Color=8388608|FontID=7|IsHidden=T|Text=https://datasheet.ciiva.com/11808/0900766b80f96399-11808223.pdf|Name=ComponentLink2URL
|RECORD=41|OwnerIndex=693|IndexInSheet=8|OwnerPartId=-1|Location.X=998|Location.Y=375|Color=8388608|FontID=1|IsHidden=T|Text=true|Name=RoHSCompliant
|RECORD=41|OwnerIndex=693|IndexInSheet=9|OwnerPartId=-1|Location.X=998|Location.Y=375|Color=8388608|FontID=1|IsHidden=T|Text=85 degC|Name=Max Operating Temperature
|RECORD=41|OwnerIndex=693|IndexInSheet=10|OwnerPartId=-1|Location.X=998|Location.Y=375|Color=8388608|FontID=1|IsHidden=T|Text=3.63 V|Name=Max Supply Voltage
|RECORD=41|OwnerIndex=693|IndexInSheet=11|OwnerPartId=-1|Location.X=998|Location.Y=375|Color=8388608|FontID=7|IsHidden=T|Text=http://www.yageo.com/|Name=ComponentLink1URL
|RECORD=41|OwnerIndex=693|IndexInSheet=12|OwnerPartId=-1|Location.X=998|Location.Y=375|Color=8388608|FontID=1|IsHidden=T|Text=2-Pin Surface Mount Device, Body 1.6 x 0.8 mm|Name=PackageDescription
|RECORD=41|OwnerIndex=693|IndexInSheet=13|OwnerPartId=-1|Location.X=998|Location.Y=375|Color=8388608|FontID=1|IsHidden=T|Text=LQFP|Name=Case\Package
|RECORD=41|OwnerIndex=693|IndexInSheet=14|OwnerPartId=-1|Location.X=998|Location.Y=375|Color=8388608|FontID=1|IsHidden=T|Text=Rev. 4, 04/2009|Name=DatasheetVersion
|RECORD=41|OwnerIndex=693|IndexInSheet=15|OwnerPartId=-1|Location.X=998|Location.Y=375|Color=8388608|FontID=1|IsHidden=T|Text=-40 degC|Name=Min Operating Temperature
|RECORD=41|OwnerIndex=693|IndexInSheet=16|OwnerPartId=-1|Location.X=998|Location.Y=375|Color=8388608|FontID=1|IsHidden=T|Text=SPI|Name=Interface
|RECORD=41|OwnerIndex=693|IndexInSheet=17|OwnerPartId=-1|Location.X=998|Location.Y=375|Color=8388608|FontID=1|IsHidden=T|Text=250|Name=Package Quantity
|RECORD=41|OwnerIndex=693|IndexInSheet=18|OwnerPartId=-1|Location.X=998|Location.Y=375|Color=8388608|FontID=1|IsHidden=T|Text=2.97 V|Name=Min Supply Voltage
|RECORD=41|OwnerIndex=693|IndexInSheet=19|OwnerPartId=-1|Location.X=998|Location.Y=375|Color=8388608|FontID=1|IsHidden=T|Text=48|Name=Pins
|RECORD=34|OwnerIndex=693|IndexInSheet=-1|OwnerPartId=-1|Location.X=1009|Location.Y=363|Color=8388608|FontID=1|Text=R42|Name=Designator|ReadOnlyState=1
|RECORD=41|OwnerIndex=693|IndexInSheet=-1|OwnerPartId=-1|Location.X=1009|Location.Y=347|Color=8388608|FontID=1|Text=DNI_49.9R|Name=Comment
|RECORD=44|OwnerIndex=693
|RECORD=45|OwnerIndex=718|IndexInSheet=-1|Description=Chip Resistor, 2-Leads, Body 1.70x0.90mm, IPC Medium Density|UseComponentLibrary=T|ModelName=RESC1608X55X25NL10T15|ModelType=PCBLIB|DatafileCount=1|ModelDatafileEntity0=RESC1608X55X25NL10T15|ModelDatafileKind0=PCBLib|IsCurrent=T|DatalinksLocked=T|DatabaseDatalinksLocked=T
|RECORD=46|OwnerIndex=719
|RECORD=48|OwnerIndex=719
|RECORD=41|OwnerIndex=721|IndexInSheet=-1|OwnerPartId=-1|Color=8388608|FontID=1|IsHidden=T|Text=2D|Name=Available Preview Images
|RECORD=45|OwnerIndex=718|IndexInSheet=-1|Description=Chip Resistor, 2-Leads, Body 1.70x0.90mm, IPC Low Density|UseComponentLibrary=T|ModelName=RESC1608X55X25ML10T15|ModelType=PCBLIB|DatafileCount=1|ModelDatafileEntity0=RESC1608X55X25ML10T15|ModelDatafileKind0=PCBLib|DatalinksLocked=T|DatabaseDatalinksLocked=T
|RECORD=46|OwnerIndex=723
|RECORD=48|OwnerIndex=723
|RECORD=41|OwnerIndex=725|IndexInSheet=-1|OwnerPartId=-1|Color=8388608|FontID=1|IsHidden=T|Text=2D|Name=Available Preview Images
|RECORD=45|OwnerIndex=718|IndexInSheet=-1|Description=Chip Resistor, 2-Leads, Body 1.70x0.90mm, IPC High Density|UseComponentLibrary=T|ModelName=RESC1608X55X25LL10T15|ModelType=PCBLIB|DatafileCount=1|ModelDatafileEntity0=RESC1608X55X25LL10T15|ModelDatafileKind0=PCBLib|DatalinksLocked=T|DatabaseDatalinksLocked=T
|RECORD=46|OwnerIndex=727
|RECORD=48|OwnerIndex=727
|RECORD=41|OwnerIndex=729|IndexInSheet=-1|OwnerPartId=-1|Color=8388608|FontID=1|IsHidden=T|Text=2D|Name=Available Preview Images
|RECORD=17|IndexInSheet=99|OwnerPartId=-1|Style=1|ShowNetName=T|Location.X=1100|Location.Y=360|Color=255|FontID=1|Text=MAC_PPS_IN|IsCrossSheetConnector=T
|RECORD=1|LibReference=SA53_Header|PartCount=2|DisplayModeCount=1|IndexInSheet=100|OwnerPartId=-1|Location.X=830|Location.Y=540|CurrentPartId=1|LibraryPath=*|SourceLibraryName=FPGA_CONN.SchLib|TargetFileName=*|AreaColor=11599871|Color=128|PartIDLocked=T|DesignItemId=SA53_Header|AllPinCount=20
|RECORD=41|OwnerIndex=732|OwnerPartId=-1|Location.X=798|Location.Y=670|Color=8388608|FontID=1|IsHidden=T|Text=Digi-Key|Name=Supplier 1|ReadOnlyState=3
|RECORD=14|OwnerIndex=732|IsNotAccesible=T|IndexInSheet=1|OwnerPartId=1|Location.X=830|Location.Y=540|Corner.X=930|Corner.Y=670|Color=128|AreaColor=11599871|IsSolid=T
|RECORD=2|OwnerIndex=732|OwnerPartId=1|FormalType=1|Electrical=4|PinConglomerate=58|PinLength=30|Location.X=830|Location.Y=660|Name=1|Designator=1|SwapIDPart=Ž&Ž||PinPropagationDelay=0.000000E+000
|RECORD=2|OwnerIndex=732|OwnerPartId=1|FormalType=1|Electrical=4|PinConglomerate=58|PinLength=30|Location.X=830|Location.Y=650|Name=3|Designator=3|SwapIDPart=Ž&Ž||PinPropagationDelay=0.000000E+000
|RECORD=2|OwnerIndex=732|OwnerPartId=1|FormalType=1|Electrical=4|PinConglomerate=58|PinLength=30|Location.X=830|Location.Y=640|Name=5|Designator=5|SwapIDPart=Ž&Ž||PinPropagationDelay=0.000000E+000
|RECORD=2|OwnerIndex=732|OwnerPartId=1|FormalType=1|Electrical=4|PinConglomerate=58|PinLength=30|Location.X=830|Location.Y=630|Name=7|Designator=7|SwapIDPart=Ž&Ž||PinPropagationDelay=0.000000E+000
|RECORD=2|OwnerIndex=732|OwnerPartId=1|FormalType=1|Electrical=4|PinConglomerate=58|PinLength=30|Location.X=830|Location.Y=610|Name=10|Designator=10|SwapIDPart=Ž&Ž||PinPropagationDelay=0.000000E+000
|RECORD=2|OwnerIndex=732|OwnerPartId=1|FormalType=1|Electrical=4|PinConglomerate=58|PinLength=30|Location.X=830|Location.Y=600|Name=11|Designator=11|SwapIDPart=Ž&Ž||PinPropagationDelay=0.000000E+000
|RECORD=2|OwnerIndex=732|OwnerPartId=1|FormalType=1|Electrical=4|PinConglomerate=58|PinLength=30|Location.X=830|Location.Y=590|Name=12|Designator=12|SwapIDPart=Ž&Ž||PinPropagationDelay=0.000000E+000
|RECORD=2|OwnerIndex=732|OwnerPartId=1|FormalType=1|Electrical=4|PinConglomerate=58|PinLength=30|Location.X=830|Location.Y=580|Name=13|Designator=13|SwapIDPart=Ž&Ž||PinPropagationDelay=0.000000E+000
|RECORD=2|OwnerIndex=732|OwnerPartId=1|FormalType=1|Electrical=4|PinConglomerate=58|PinLength=30|Location.X=830|Location.Y=570|Name=14|Designator=14|SwapIDPart=Ž&Ž||PinPropagationDelay=0.000000E+000
|RECORD=2|OwnerIndex=732|OwnerPartId=1|FormalType=1|Electrical=4|PinConglomerate=58|PinLength=30|Location.X=830|Location.Y=560|Name=16|Designator=16|SwapIDPart=Ž&Ž||PinPropagationDelay=0.000000E+000
|RECORD=2|OwnerIndex=732|OwnerPartId=1|FormalType=1|Electrical=4|PinConglomerate=58|PinLength=30|Location.X=830|Location.Y=550|Name=18|Designator=18|SwapIDPart=Ž&Ž||PinPropagationDelay=0.000000E+000
|RECORD=41|OwnerIndex=732|IndexInSheet=13|OwnerPartId=-1|Location.X=830|Location.Y=520|Color=8388608|FontID=1|Text=WM24007CT-ND|Name=Supplier Part Number 1|ReadOnlyState=3
|RECORD=2|OwnerIndex=732|OwnerPartId=1|FormalType=1|Electrical=4|PinConglomerate=56|PinLength=30|Location.X=930|Location.Y=660|Name=2|Designator=2|SwapIDPart=Ž&Ž||PinPropagationDelay=0.000000E+000
|RECORD=2|OwnerIndex=732|OwnerPartId=1|FormalType=1|Electrical=4|PinConglomerate=56|PinLength=30|Location.X=930|Location.Y=650|Name=4|Designator=4|SwapIDPart=Ž&Ž||PinPropagationDelay=0.000000E+000
|RECORD=2|OwnerIndex=732|OwnerPartId=1|FormalType=1|Electrical=4|PinConglomerate=56|PinLength=30|Location.X=930|Location.Y=640|Name=6|Designator=6|SwapIDPart=Ž&Ž||PinPropagationDelay=0.000000E+000
|RECORD=2|OwnerIndex=732|OwnerPartId=1|FormalType=1|Electrical=4|PinConglomerate=56|PinLength=30|Location.X=930|Location.Y=620|Name=17|Designator=17|SwapIDPart=Ž&Ž||PinPropagationDelay=0.000000E+000
|RECORD=2|OwnerIndex=732|OwnerPartId=1|FormalType=1|Electrical=4|PinConglomerate=56|PinLength=30|Location.X=930|Location.Y=610|Name=19|Designator=19|SwapIDPart=Ž&Ž||PinPropagationDelay=0.000000E+000
|RECORD=2|OwnerIndex=732|OwnerPartId=1|FormalType=1|Electrical=4|PinConglomerate=56|PinLength=30|Location.X=930|Location.Y=590|Name=20|Designator=20|SwapIDPart=Ž&Ž||PinPropagationDelay=0.000000E+000
|RECORD=2|OwnerIndex=732|OwnerPartId=1|FormalType=1|Electrical=4|PinConglomerate=56|PinLength=30|Location.X=930|Location.Y=570|Name=8|Designator=8|SwapIDPart=Ž&Ž||PinPropagationDelay=0.000000E+000
|RECORD=2|OwnerIndex=732|OwnerPartId=1|FormalType=1|Electrical=4|PinConglomerate=56|PinLength=30|Location.X=930|Location.Y=560|Name=9|Designator=9|SwapIDPart=Ž&Ž||PinPropagationDelay=0.000000E+000
|RECORD=2|OwnerIndex=732|OwnerPartId=1|FormalType=1|Electrical=4|PinConglomerate=56|PinLength=30|Location.X=930|Location.Y=550|Name=15|Designator=15|SwapIDPart=Ž&Ž||PinPropagationDelay=0.000000E+000
|RECORD=34|OwnerIndex=732|IndexInSheet=-1|OwnerPartId=-1|Location.X=830|Location.Y=670|Color=8388608|FontID=1|Text=J31|Name=Designator|ReadOnlyState=1
|RECORD=41|OwnerIndex=732|IndexInSheet=-1|OwnerPartId=-1|Location.X=830|Location.Y=530|Color=8388608|FontID=1|Text=SA53_Header|Name=Comment
|RECORD=44|OwnerIndex=732
|RECORD=45|OwnerIndex=778|IndexInSheet=-1|ModelName=SA53_Header|ModelType=PCBLIB|DatafileCount=1|ModelDatafileEntity0=SA53_Header|ModelDatafileKind0=PCBLib|IsCurrent=T
|RECORD=46|OwnerIndex=779
|RECORD=48|OwnerIndex=779
|RECORD=22|IndexInSheet=101|OwnerPartId=-1|Location.X=800|Location.Y=610|Color=255|Orientation=1|Symbol=Thin Cross|IsActive=T|SuppressAll=T
|RECORD=22|IndexInSheet=102|OwnerPartId=-1|Location.X=800|Location.Y=600|Color=255|Orientation=1|Symbol=Thin Cross|IsActive=T|SuppressAll=T
|RECORD=22|IndexInSheet=103|OwnerPartId=-1|Location.X=800|Location.Y=590|Color=255|Orientation=1|Symbol=Thin Cross|IsActive=T|SuppressAll=T
|RECORD=22|IndexInSheet=104|OwnerPartId=-1|Location.X=800|Location.Y=580|Color=255|Orientation=1|Symbol=Thin Cross|IsActive=T|SuppressAll=T
|RECORD=22|IndexInSheet=105|OwnerPartId=-1|Location.X=800|Location.Y=570|Color=255|Orientation=1|Symbol=Thin Cross|IsActive=T|SuppressAll=T
|RECORD=22|IndexInSheet=106|OwnerPartId=-1|Location.X=800|Location.Y=560|Color=255|Orientation=1|Symbol=Thin Cross|IsActive=T|SuppressAll=T
|RECORD=22|IndexInSheet=107|OwnerPartId=-1|Location.X=800|Location.Y=550|Color=255|Orientation=1|Symbol=Thin Cross|IsActive=T|SuppressAll=T
|RECORD=17|IndexInSheet=108|OwnerPartId=-1|Style=4|ShowNetName=T|Location.X=970|Location.Y=540|Orientation=3|Color=128|FontID=1|Text=GND
|RECORD=1|LibReference=RES|PartCount=2|DisplayModeCount=2|IndexInSheet=109|OwnerPartId=-1|Location.X=1450|Location.Y=1000|CurrentPartId=1|SourceLibraryName=Altium Content Vault|TargetFileName=*|AreaColor=11599871|Color=128|PartIDLocked=F|DesignItemId=CMP-2003-04873-1|AllPinCount=2
|RECORD=2|OwnerIndex=790|OwnerPartId=1|OwnerPartDisplayMode=1|FormalType=1|Electrical=4|PinConglomerate=32|PinLength=10|Location.X=1470|Location.Y=990|Name=2|Designator=2|PinPropagationDelay=0.000000E+000
|RECORD=2|OwnerIndex=790|OwnerPartId=1|OwnerPartDisplayMode=1|FormalType=1|Electrical=4|PinConglomerate=34|PinLength=10|Location.X=1450|Location.Y=990|Name=1|Designator=1|PinPropagationDelay=0.000000E+000
|RECORD=14|OwnerIndex=790|IsNotAccesible=T|IndexInSheet=2|OwnerPartId=1|OwnerPartDisplayMode=1|Location.X=1450|Location.Y=986|Corner.X=1470|Corner.Y=994|LineWidth=1|Color=16711680|AreaColor=11599871
|RECORD=2|OwnerIndex=790|OwnerPartId=1|FormalType=1|Electrical=4|PinConglomerate=32|PinLength=10|Location.X=1470|Location.Y=990|Name=2|Designator=2|PinPropagationDelay=0.000000E+000
|RECORD=2|OwnerIndex=790|OwnerPartId=1|FormalType=1|Electrical=4|PinConglomerate=34|PinLength=10|Location.X=1450|Location.Y=990|Name=1|Designator=1|PinPropagationDelay=0.000000E+000
|RECORD=6|OwnerIndex=790|IsNotAccesible=T|IndexInSheet=5|OwnerPartId=1|LineWidth=1|Color=16711680|LocationCount=10|X1=1470|Y1=990|X2=1466|Y2=990|X3=1465|Y3=988|X4=1463|Y4=992|X5=1461|Y5=988|X6=1459|Y6=992|X7=1457|Y7=988|X8=1455|Y8=992|X9=1454|Y9=990|X10=1450|Y10=990
|RECORD=41|OwnerIndex=790|IndexInSheet=6|OwnerPartId=-1|Location.X=1438|Location.Y=1003|Color=8388608|FontID=1|IsHidden=T|Text=CRCW12060000Z0EAHP|Name=Part Number
|RECORD=41|OwnerIndex=790|IndexInSheet=7|OwnerPartId=-1|Location.X=1438|Location.Y=1003|Color=8388608|FontID=1|IsHidden=T|Text=Vishay Dale|Name=Manufacturer
|RECORD=34|OwnerIndex=790|IndexInSheet=-1|OwnerPartId=-1|Location.X=1449|Location.Y=993|Color=8388608|FontID=1|Text=R45|Name=Designator|ReadOnlyState=1
|RECORD=41|OwnerIndex=790|IndexInSheet=-1|OwnerPartId=-1|Location.X=1449|Location.Y=977|Color=8388608|FontID=1|Text=0_5%_1206|Name=Comment
|RECORD=44|OwnerIndex=790
|RECORD=45|OwnerIndex=805|IndexInSheet=-1|Description=Chip Resistor, 2-Leads, Body 3.10x1.60mm, IPC Low Density|UseComponentLibrary=T|ModelName=RESC3116X65X50ML20T20|ModelType=PCBLIB|DatafileCount=1|ModelDatafileEntity0=RESC3116X65X50ML20T20|ModelDatafileKind0=PCBLib|IsCurrent=T|DatalinksLocked=T|DatabaseDatalinksLocked=T
|RECORD=46|OwnerIndex=806
|RECORD=48|OwnerIndex=806
|RECORD=41|OwnerIndex=808|IndexInSheet=-1|OwnerPartId=-1|Color=8388608|FontID=1|IsHidden=T|Text=2D|Name=Available Preview Images
|RECORD=45|OwnerIndex=805|IndexInSheet=-1|Description=Chip Resistor, 2-Leads, Body 3.10x1.60mm, IPC High Density|UseComponentLibrary=T|ModelName=RESC3116X65X50LL20T20|ModelType=PCBLIB|DatafileCount=1|ModelDatafileEntity0=RESC3116X65X50LL20T20|ModelDatafileKind0=PCBLib|DatalinksLocked=T|DatabaseDatalinksLocked=T
|RECORD=46|OwnerIndex=810
|RECORD=48|OwnerIndex=810
|RECORD=41|OwnerIndex=812|IndexInSheet=-1|OwnerPartId=-1|Color=8388608|FontID=1|IsHidden=T|Text=2D|Name=Available Preview Images
|RECORD=45|OwnerIndex=805|IndexInSheet=-1|Description=Chip Resistor, 2-Leads, Body 3.10x1.60mm, IPC Medium Density|UseComponentLibrary=T|ModelName=RESC3116X65X50NL20T20|ModelType=PCBLIB|DatafileCount=1|ModelDatafileEntity0=RESC3116X65X50NL20T20|ModelDatafileKind0=PCBLib|DatalinksLocked=T|DatabaseDatalinksLocked=T
|RECORD=46|OwnerIndex=814
|RECORD=48|OwnerIndex=814
|RECORD=41|OwnerIndex=816|IndexInSheet=-1|OwnerPartId=-1|Color=8388608|FontID=1|IsHidden=T|Text=2D|Name=Available Preview Images
|RECORD=1|LibReference=RES|PartCount=2|DisplayModeCount=2|IndexInSheet=110|OwnerPartId=-1|Location.X=1450|Location.Y=960|CurrentPartId=1|SourceLibraryName=Altium Content Vault|TargetFileName=*|AreaColor=11599871|Color=128|PartIDLocked=F|DesignItemId=CMP-2003-04873-1|AllPinCount=2|ComponentKindVersion2=5
|RECORD=2|OwnerIndex=818|OwnerPartId=1|OwnerPartDisplayMode=1|FormalType=1|Electrical=4|PinConglomerate=32|PinLength=10|Location.X=1470|Location.Y=950|Name=2|Designator=2|PinPropagationDelay=0.000000E+000
|RECORD=2|OwnerIndex=818|OwnerPartId=1|OwnerPartDisplayMode=1|FormalType=1|Electrical=4|PinConglomerate=34|PinLength=10|Location.X=1450|Location.Y=950|Name=1|Designator=1|PinPropagationDelay=0.000000E+000
|RECORD=14|OwnerIndex=818|IsNotAccesible=T|IndexInSheet=2|OwnerPartId=1|OwnerPartDisplayMode=1|Location.X=1450|Location.Y=946|Corner.X=1470|Corner.Y=954|LineWidth=1|Color=16711680|AreaColor=11599871
|RECORD=2|OwnerIndex=818|OwnerPartId=1|FormalType=1|Electrical=4|PinConglomerate=32|PinLength=10|Location.X=1470|Location.Y=950|Name=2|Designator=2|PinPropagationDelay=0.000000E+000
|RECORD=2|OwnerIndex=818|OwnerPartId=1|FormalType=1|Electrical=4|PinConglomerate=34|PinLength=10|Location.X=1450|Location.Y=950|Name=1|Designator=1|PinPropagationDelay=0.000000E+000
|RECORD=6|OwnerIndex=818|IsNotAccesible=T|IndexInSheet=5|OwnerPartId=1|LineWidth=1|Color=16711680|LocationCount=10|X1=1470|Y1=950|X2=1466|Y2=950|X3=1465|Y3=948|X4=1463|Y4=952|X5=1461|Y5=948|X6=1459|Y6=952|X7=1457|Y7=948|X8=1455|Y8=952|X9=1454|Y9=950|X10=1450|Y10=950
|RECORD=41|OwnerIndex=818|IndexInSheet=6|OwnerPartId=-1|Location.X=1438|Location.Y=963|Color=8388608|FontID=1|IsHidden=T|Text=CRCW12060000Z0EAHP|Name=Part Number
|RECORD=41|OwnerIndex=818|IndexInSheet=7|OwnerPartId=-1|Location.X=1438|Location.Y=963|Color=8388608|FontID=1|IsHidden=T|Text=Vishay Dale|Name=Manufacturer
|RECORD=34|OwnerIndex=818|IndexInSheet=-1|OwnerPartId=-1|Location.X=1449|Location.Y=953|Color=8388608|FontID=1|Text=R46|Name=Designator|ReadOnlyState=1
|RECORD=41|OwnerIndex=818|IndexInSheet=-1|OwnerPartId=-1|Location.X=1449|Location.Y=937|Color=8388608|FontID=1|Text=DNI_0_5%_1206|Name=Comment
|RECORD=44|OwnerIndex=818
|RECORD=45|OwnerIndex=833|IndexInSheet=-1|Description=Chip Resistor, 2-Leads, Body 3.10x1.60mm, IPC Low Density|UseComponentLibrary=T|ModelName=RESC3116X65X50ML20T20|ModelType=PCBLIB|DatafileCount=1|ModelDatafileEntity0=RESC3116X65X50ML20T20|ModelDatafileKind0=PCBLib|IsCurrent=T|DatalinksLocked=T|DatabaseDatalinksLocked=T
|RECORD=46|OwnerIndex=834
|RECORD=48|OwnerIndex=834
|RECORD=41|OwnerIndex=836|IndexInSheet=-1|OwnerPartId=-1|Color=8388608|FontID=1|IsHidden=T|Text=2D|Name=Available Preview Images
|RECORD=45|OwnerIndex=833|IndexInSheet=-1|Description=Chip Resistor, 2-Leads, Body 3.10x1.60mm, IPC High Density|UseComponentLibrary=T|ModelName=RESC3116X65X50LL20T20|ModelType=PCBLIB|DatafileCount=1|ModelDatafileEntity0=RESC3116X65X50LL20T20|ModelDatafileKind0=PCBLib|DatalinksLocked=T|DatabaseDatalinksLocked=T
|RECORD=46|OwnerIndex=838
|RECORD=48|OwnerIndex=838
|RECORD=41|OwnerIndex=840|IndexInSheet=-1|OwnerPartId=-1|Color=8388608|FontID=1|IsHidden=T|Text=2D|Name=Available Preview Images
|RECORD=45|OwnerIndex=833|IndexInSheet=-1|Description=Chip Resistor, 2-Leads, Body 3.10x1.60mm, IPC Medium Density|UseComponentLibrary=T|ModelName=RESC3116X65X50NL20T20|ModelType=PCBLIB|DatafileCount=1|ModelDatafileEntity0=RESC3116X65X50NL20T20|ModelDatafileKind0=PCBLib|DatalinksLocked=T|DatabaseDatalinksLocked=T
|RECORD=46|OwnerIndex=842
|RECORD=48|OwnerIndex=842
|RECORD=41|OwnerIndex=844|IndexInSheet=-1|OwnerPartId=-1|Color=8388608|FontID=1|IsHidden=T|Text=2D|Name=Available Preview Images
|RECORD=17|IndexInSheet=111|OwnerPartId=-1|ShowNetName=T|Location.X=1510|Location.Y=1030|Orientation=1|Color=128|FontID=1|Text=+5.0V
|RECORD=27|IndexInSheet=112|OwnerPartId=-1|LineWidth=1|Color=8388608|LocationCount=2|Y1=1100|X2=100|Y2=1100
|RECORD=27|IndexInSheet=113|OwnerPartId=-1|LineWidth=1|Color=8388608|LocationCount=2|X1=718|Y1=967|X2=768|Y2=967
|RECORD=27|IndexInSheet=114|OwnerPartId=-1|LineWidth=1|Color=8388608|LocationCount=2|X1=718|Y1=987|X2=768|Y2=987
|RECORD=27|IndexInSheet=115|OwnerPartId=-1|LineWidth=1|Color=8388608|LocationCount=2|X1=768|Y1=957|X2=748|Y2=957
|RECORD=27|IndexInSheet=116|OwnerPartId=-1|LineWidth=1|Color=8388608|LocationCount=2|X1=960|Y1=740|X2=980|Y2=740
|RECORD=27|IndexInSheet=117|OwnerPartId=-1|LineWidth=1|Color=8388608|LocationCount=2|X1=960|Y1=750|X2=980|Y2=750
|RECORD=27|IndexInSheet=118|OwnerPartId=-1|LineWidth=1|Color=8388608|LocationCount=2|X1=978|Y1=967|X2=1018|Y2=967
|RECORD=27|IndexInSheet=119|OwnerPartId=-1|LineWidth=1|Color=8388608|LocationCount=2|X1=978|Y1=977|X2=1018|Y2=977
|RECORD=27|IndexInSheet=120|OwnerPartId=-1|LineWidth=1|Color=8388608|LocationCount=2|X1=978|Y1=987|X2=1018|Y2=987
|RECORD=27|IndexInSheet=121|OwnerPartId=-1|LineWidth=1|Color=8388608|LocationCount=4|X1=1340|Y1=920|X2=1340|Y2=906|X3=1281|Y3=906|X4=1281|Y4=916
|RECORD=27|IndexInSheet=122|OwnerPartId=-1|LineWidth=1|Color=8388608|LocationCount=4|X1=970|Y1=260|X2=990|Y2=260|X3=1040|Y3=260|X4=1110|Y4=260
|RECORD=27|IndexInSheet=123|OwnerPartId=-1|LineWidth=1|Color=8388608|LocationCount=2|X1=1010|Y1=230|X2=1010|Y2=290
|RECORD=27|IndexInSheet=124|OwnerPartId=-1|LineWidth=1|Color=8388608|LocationCount=2|X1=1040|Y1=230|X2=1040|Y2=260
|RECORD=27|IndexInSheet=125|OwnerPartId=-1|LineWidth=1|Color=8388608|LocationCount=3|X1=1110|Y1=290|X2=1010|Y2=290|X3=970|Y3=290
|RECORD=27|IndexInSheet=126|OwnerPartId=-1|LineWidth=1|Color=8388608|LocationCount=2|X1=1010|Y1=170|X2=1010|Y2=190
|RECORD=27|IndexInSheet=127|OwnerPartId=-1|LineWidth=1|Color=8388608|LocationCount=2|X1=1040|Y1=170|X2=1040|Y2=190
|RECORD=27|IndexInSheet=128|OwnerPartId=-1|LineWidth=1|Color=8388608|LocationCount=2|X1=1080|Y1=170|X2=1080|Y2=190
|RECORD=27|IndexInSheet=129|OwnerPartId=-1|LineWidth=1|Color=8388608|LocationCount=3|X1=1080|Y1=220|X2=1080|Y2=230|X3=1110|Y3=230
|RECORD=27|IndexInSheet=130|OwnerPartId=-1|LineWidth=1|Color=8388608|LocationCount=2|X1=1080|Y1=230|X2=1080|Y2=320
|RECORD=27|IndexInSheet=131|OwnerPartId=-1|LineWidth=1|Color=8388608|LocationCount=2|X1=1220|Y1=290|X2=1280|Y2=290
|RECORD=27|IndexInSheet=132|OwnerPartId=-1|LineWidth=1|Color=8388608|LocationCount=2|X1=1220|Y1=280|X2=1280|Y2=280
|RECORD=27|IndexInSheet=133|OwnerPartId=-1|LineWidth=1|Color=8388608|LocationCount=2|X1=1220|Y1=260|X2=1280|Y2=260
|RECORD=27|IndexInSheet=134|OwnerPartId=-1|LineWidth=1|Color=8388608|LocationCount=2|X1=1220|Y1=250|X2=1280|Y2=250
|RECORD=27|IndexInSheet=135|OwnerPartId=-1|LineWidth=1|Color=8388608|LocationCount=3|X1=1220|Y1=230|X2=1260|Y2=230|X3=1260|Y3=170
|RECORD=27|IndexInSheet=136|OwnerPartId=-1|LineWidth=1|Color=8388608|LocationCount=3|X1=190|Y1=310|X2=230|Y2=310|X3=230|Y3=300
|RECORD=27|IndexInSheet=137|OwnerPartId=-1|LineWidth=1|Color=8388608|LocationCount=3|X1=190|Y1=250|X2=230|Y2=250|X3=230|Y3=260
|RECORD=27|IndexInSheet=138|OwnerPartId=-1|LineWidth=1|Color=8388608|LocationCount=4|X1=230|Y1=250|X2=260|Y2=250|X3=260|Y3=260|X4=320|Y4=260
|RECORD=27|IndexInSheet=139|OwnerPartId=-1|LineWidth=1|Color=8388608|LocationCount=4|X1=320|Y1=270|X2=260|Y2=270|X3=260|Y3=310|X4=230|Y4=310
|RECORD=27|IndexInSheet=140|OwnerPartId=-1|LineWidth=1|Color=8388608|LocationCount=3|X1=320|Y1=210|X2=290|Y2=210|X3=290|Y3=190
|RECORD=27|IndexInSheet=141|OwnerPartId=-1|LineWidth=1|Color=8388608|LocationCount=2|X1=290|Y1=210|X2=290|Y2=330
|RECORD=27|IndexInSheet=142|OwnerPartId=-1|LineWidth=1|Color=8388608|LocationCount=3|X1=440|Y1=210|X2=480|Y2=210|X3=480|Y3=130
|RECORD=27|IndexInSheet=143|OwnerPartId=-1|LineWidth=1|Color=8388608|LocationCount=2|X1=290|Y1=130|X2=290|Y2=160
|RECORD=27|IndexInSheet=144|OwnerPartId=-1|LineWidth=1|Color=8388608|LocationCount=2|X1=460|Y1=270|X2=440|Y2=270
|RECORD=27|IndexInSheet=145|OwnerPartId=-1|LineWidth=1|Color=8388608|LocationCount=4|X1=768|Y1=977|X2=748|Y2=977|X3=748|Y3=957|X4=748|Y4=937
|RECORD=27|IndexInSheet=146|OwnerPartId=-1|LineWidth=1|Color=8388608|LocationCount=2|X1=980|Y1=930|X2=1040|Y2=930
|RECORD=27|IndexInSheet=147|OwnerPartId=-1|LineWidth=1|Color=8388608|LocationCount=2|X1=1040|Y1=940|X2=980|Y2=940
|RECORD=27|IndexInSheet=148|OwnerPartId=-1|LineWidth=1|Color=8388608|LocationCount=2|X1=1281|Y1=950|X2=1281|Y2=946
|RECORD=27|IndexInSheet=149|OwnerPartId=-1|LineWidth=1|Color=8388608|LocationCount=2|X1=430|Y1=320|X2=460|Y2=320
|RECORD=27|IndexInSheet=150|OwnerPartId=-1|LineWidth=1|Color=8388608|LocationCount=3|X1=500|Y1=320|X2=540|Y2=320|X3=540|Y3=270
|RECORD=27|IndexInSheet=151|OwnerPartId=-1|LineWidth=1|Color=8388608|LocationCount=2|X1=1040|Y1=360|X2=1100|Y2=360
|RECORD=27|IndexInSheet=152|OwnerPartId=-1|LineWidth=1|Color=8388608|LocationCount=3|X1=1000|Y1=360|X2=990|Y2=360|X3=990|Y3=260
|RECORD=27|IndexInSheet=153|OwnerPartId=-1|LineWidth=1|Color=8388608|LocationCount=3|X1=580|Y1=270|X2=540|Y2=270|X3=500|Y3=270
|RECORD=27|IndexInSheet=154|OwnerPartId=-1|LineWidth=1|Color=8388608|LocationCount=3|X1=590|Y1=820|X2=720|Y2=820|X3=780|Y3=820
|RECORD=27|IndexInSheet=155|OwnerPartId=-1|LineWidth=1|Color=8388608|LocationCount=3|X1=780|Y1=830|X2=730|Y2=830|X3=590|Y3=830
|RECORD=27|IndexInSheet=156|OwnerPartId=-1|LineWidth=1|Color=8388608|LocationCount=3|X1=780|Y1=840|X2=740|Y2=840|X3=590|Y3=840
|RECORD=27|IndexInSheet=157|OwnerPartId=-1|LineWidth=1|Color=8388608|LocationCount=3|X1=780|Y1=850|X2=750|Y2=850|X3=590|Y3=850
|RECORD=27|IndexInSheet=158|OwnerPartId=-1|LineWidth=1|Color=8388608|LocationCount=3|X1=800|Y1=660|X2=750|Y2=660|X3=750|Y3=850
|RECORD=27|IndexInSheet=159|OwnerPartId=-1|LineWidth=1|Color=8388608|LocationCount=3|X1=800|Y1=650|X2=740|Y2=650|X3=740|Y3=840
|RECORD=27|IndexInSheet=160|OwnerPartId=-1|LineWidth=1|Color=8388608|LocationCount=3|X1=800|Y1=640|X2=730|Y2=640|X3=730|Y3=830
|RECORD=27|IndexInSheet=161|OwnerPartId=-1|LineWidth=1|Color=8388608|LocationCount=3|X1=800|Y1=630|X2=720|Y2=630|X3=720|Y3=820
|RECORD=27|IndexInSheet=162|OwnerPartId=-1|LineWidth=1|Color=8388608|LocationCount=3|X1=1210|Y1=780|X2=1090|Y2=780|X3=960|Y3=780
|RECORD=27|IndexInSheet=163|OwnerPartId=-1|LineWidth=1|Color=8388608|LocationCount=3|X1=1210|Y1=800|X2=1070|Y2=800|X3=960|Y3=800
|RECORD=27|IndexInSheet=164|OwnerPartId=-1|LineWidth=1|Color=8388608|LocationCount=3|X1=1210|Y1=810|X2=1060|Y2=810|X3=960|Y3=810
|RECORD=27|IndexInSheet=165|OwnerPartId=-1|LineWidth=1|Color=8388608|LocationCount=3|X1=1210|Y1=830|X2=1030|Y2=830|X3=960|Y3=830
|RECORD=27|IndexInSheet=166|OwnerPartId=-1|LineWidth=1|Color=8388608|LocationCount=3|X1=1210|Y1=840|X2=1020|Y2=840|X3=960|Y3=840
|RECORD=27|IndexInSheet=167|OwnerPartId=-1|LineWidth=1|Color=8388608|LocationCount=3|X1=1210|Y1=850|X2=1010|Y2=850|X3=960|Y3=850
|RECORD=27|IndexInSheet=168|OwnerPartId=-1|LineWidth=1|Color=8388608|LocationCount=5|X1=960|Y1=760|X2=980|Y2=760|X3=980|Y3=750|X4=980|Y4=740|X5=980|Y5=720
|RECORD=27|IndexInSheet=169|OwnerPartId=-1|LineWidth=1|Color=8388608|LocationCount=3|X1=960|Y1=660|X2=1010|Y2=660|X3=1010|Y3=850
|RECORD=27|IndexInSheet=170|OwnerPartId=-1|LineWidth=1|Color=8388608|LocationCount=3|X1=960|Y1=650|X2=1020|Y2=650|X3=1020|Y3=840
|RECORD=27|IndexInSheet=171|OwnerPartId=-1|LineWidth=1|Color=8388608|LocationCount=3|X1=960|Y1=640|X2=1030|Y2=640|X3=1030|Y3=830
|RECORD=27|IndexInSheet=172|OwnerPartId=-1|LineWidth=1|Color=8388608|LocationCount=3|X1=960|Y1=620|X2=1060|Y2=620|X3=1060|Y3=810
|RECORD=27|IndexInSheet=173|OwnerPartId=-1|LineWidth=1|Color=8388608|LocationCount=3|X1=960|Y1=610|X2=1070|Y2=610|X3=1070|Y3=800
|RECORD=27|IndexInSheet=174|OwnerPartId=-1|LineWidth=1|Color=8388608|LocationCount=3|X1=960|Y1=590|X2=1090|Y2=590|X3=1090|Y3=780
|RECORD=27|IndexInSheet=175|OwnerPartId=-1|LineWidth=1|Color=8388608|LocationCount=5|X1=960|Y1=570|X2=970|Y2=570|X3=970|Y3=560|X4=970|Y4=550|X5=970|Y5=540
|RECORD=27|IndexInSheet=176|OwnerPartId=-1|LineWidth=1|Color=8388608|LocationCount=2|X1=960|Y1=550|X2=970|Y2=550
|RECORD=27|IndexInSheet=177|OwnerPartId=-1|LineWidth=1|Color=8388608|LocationCount=2|X1=960|Y1=560|X2=970|Y2=560
|RECORD=27|IndexInSheet=178|OwnerPartId=-1|LineWidth=1|Color=8388608|LocationCount=3|X1=1480|Y1=990|X2=1510|Y2=990|X3=1510|Y3=1030
|RECORD=27|IndexInSheet=179|OwnerPartId=-1|LineWidth=1|Color=8388608|LocationCount=3|X1=978|Y1=957|X2=978|Y2=950|X3=1281|Y3=950
|RECORD=27|IndexInSheet=180|OwnerPartId=-1|LineWidth=1|Color=8388608|LocationCount=4|X1=1281|Y1=950|X2=1340|Y2=950|X3=1390|Y3=950|X4=1440|Y4=950
|RECORD=27|IndexInSheet=181|OwnerPartId=-1|LineWidth=1|Color=8388608|LocationCount=3|X1=1440|Y1=990|X2=1390|Y2=990|X3=1390|Y3=950
|RECORD=17|IndexInSheet=182|OwnerPartId=-1|ShowNetName=T|Location.X=1560|Location.Y=1030|Orientation=1|Color=128|FontID=1|Text=+12V
|RECORD=27|IndexInSheet=183|OwnerPartId=-1|LineWidth=1|Color=8388608|LocationCount=3|X1=1480|Y1=950|X2=1560|Y2=950|X3=1560|Y3=1030
|RECORD=4|IndexInSheet=184|OwnerPartId=-1|Location.X=1460|Location.Y=870|Color=8388608|FontID=1|Text=12V and 3.3V Option for different Atomic clocks
|RECORD=25|IndexInSheet=185|OwnerPartId=-1|Location.X=1170|Location.Y=950|Color=128|FontID=1|Text=MAC_VCC
|RECORD=1|LibReference=RES|PartCount=2|DisplayModeCount=2|IndexInSheet=186|OwnerPartId=-1|Location.X=1450|Location.Y=930|CurrentPartId=1|SourceLibraryName=Altium Content Vault|TargetFileName=*|AreaColor=11599871|Color=128|PartIDLocked=F|DesignItemId=CMP-2003-04873-1|AllPinCount=2|ComponentKindVersion2=5
|RECORD=2|OwnerIndex=921|OwnerPartId=1|OwnerPartDisplayMode=1|FormalType=1|Electrical=4|PinConglomerate=32|PinLength=10|Location.X=1470|Location.Y=920|Name=2|Designator=2|PinPropagationDelay=0.000000E+000
|RECORD=2|OwnerIndex=921|OwnerPartId=1|OwnerPartDisplayMode=1|FormalType=1|Electrical=4|PinConglomerate=34|PinLength=10|Location.X=1450|Location.Y=920|Name=1|Designator=1|PinPropagationDelay=0.000000E+000
|RECORD=14|OwnerIndex=921|IsNotAccesible=T|IndexInSheet=2|OwnerPartId=1|OwnerPartDisplayMode=1|Location.X=1450|Location.Y=916|Corner.X=1470|Corner.Y=924|LineWidth=1|Color=16711680|AreaColor=11599871
|RECORD=2|OwnerIndex=921|OwnerPartId=1|FormalType=1|Electrical=4|PinConglomerate=32|PinLength=10|Location.X=1470|Location.Y=920|Name=2|Designator=2|PinPropagationDelay=0.000000E+000
|RECORD=2|OwnerIndex=921|OwnerPartId=1|FormalType=1|Electrical=4|PinConglomerate=34|PinLength=10|Location.X=1450|Location.Y=920|Name=1|Designator=1|PinPropagationDelay=0.000000E+000
|RECORD=6|OwnerIndex=921|IsNotAccesible=T|IndexInSheet=5|OwnerPartId=1|LineWidth=1|Color=16711680|LocationCount=10|X1=1470|Y1=920|X2=1466|Y2=920|X3=1465|Y3=918|X4=1463|Y4=922|X5=1461|Y5=918|X6=1459|Y6=922|X7=1457|Y7=918|X8=1455|Y8=922|X9=1454|Y9=920|X10=1450|Y10=920
|RECORD=41|OwnerIndex=921|IndexInSheet=6|OwnerPartId=-1|Location.X=1438|Location.Y=933|Color=8388608|FontID=1|IsHidden=T|Text=CRCW12060000Z0EAHP|Name=Part Number
|RECORD=41|OwnerIndex=921|IndexInSheet=7|OwnerPartId=-1|Location.X=1438|Location.Y=933|Color=8388608|FontID=1|IsHidden=T|Text=Vishay Dale|Name=Manufacturer
|RECORD=34|OwnerIndex=921|IndexInSheet=-1|OwnerPartId=-1|Location.X=1449|Location.Y=923|Color=8388608|FontID=1|Text=R47|Name=Designator|ReadOnlyState=1
|RECORD=41|OwnerIndex=921|IndexInSheet=-1|OwnerPartId=-1|Location.X=1449|Location.Y=907|Color=8388608|FontID=1|Text=DNI_0_5%_1206|Name=Comment
|RECORD=44|OwnerIndex=921
|RECORD=45|OwnerIndex=936|IndexInSheet=-1|Description=Chip Resistor, 2-Leads, Body 3.10x1.60mm, IPC Low Density|UseComponentLibrary=T|ModelName=RESC3116X65X50ML20T20|ModelType=PCBLIB|DatafileCount=1|ModelDatafileEntity0=RESC3116X65X50ML20T20|ModelDatafileKind0=PCBLib|IsCurrent=T|DatalinksLocked=T|DatabaseDatalinksLocked=T
|RECORD=46|OwnerIndex=937
|RECORD=48|OwnerIndex=937
|RECORD=41|OwnerIndex=939|IndexInSheet=-1|OwnerPartId=-1|Color=8388608|FontID=1|IsHidden=T|Text=2D|Name=Available Preview Images
|RECORD=45|OwnerIndex=936|IndexInSheet=-1|Description=Chip Resistor, 2-Leads, Body 3.10x1.60mm, IPC High Density|UseComponentLibrary=T|ModelName=RESC3116X65X50LL20T20|ModelType=PCBLIB|DatafileCount=1|ModelDatafileEntity0=RESC3116X65X50LL20T20|ModelDatafileKind0=PCBLib|DatalinksLocked=T|DatabaseDatalinksLocked=T
|RECORD=46|OwnerIndex=941
|RECORD=48|OwnerIndex=941
|RECORD=41|OwnerIndex=943|IndexInSheet=-1|OwnerPartId=-1|Color=8388608|FontID=1|IsHidden=T|Text=2D|Name=Available Preview Images
|RECORD=45|OwnerIndex=936|IndexInSheet=-1|Description=Chip Resistor, 2-Leads, Body 3.10x1.60mm, IPC Medium Density|UseComponentLibrary=T|ModelName=RESC3116X65X50NL20T20|ModelType=PCBLIB|DatafileCount=1|ModelDatafileEntity0=RESC3116X65X50NL20T20|ModelDatafileKind0=PCBLib|DatalinksLocked=T|DatabaseDatalinksLocked=T
|RECORD=46|OwnerIndex=945
|RECORD=48|OwnerIndex=945
|RECORD=41|OwnerIndex=947|IndexInSheet=-1|OwnerPartId=-1|Color=8388608|FontID=1|IsHidden=T|Text=2D|Name=Available Preview Images
|RECORD=17|IndexInSheet=187|OwnerPartId=-1|ShowNetName=T|Location.X=1600|Location.Y=1030|Orientation=1|Color=128|FontID=1|Text=+3.3V
|RECORD=27|IndexInSheet=188|OwnerPartId=-1|LineWidth=1|Color=8388608|LocationCount=3|X1=1480|Y1=920|X2=1600|Y2=920|X3=1600|Y3=1030
|RECORD=27|IndexInSheet=189|OwnerPartId=-1|LineWidth=1|Color=8388608|LocationCount=3|X1=1440|Y1=920|X2=1390|Y2=920|X3=1390|Y3=950
|RECORD=29|IndexInSheet=-1|OwnerPartId=-1|Location.X=230|Location.Y=250|Color=128
|RECORD=29|IndexInSheet=-1|OwnerPartId=-1|Location.X=230|Location.Y=310|Color=128
|RECORD=29|IndexInSheet=-1|OwnerPartId=-1|Location.X=290|Location.Y=210|Color=128
|RECORD=29|IndexInSheet=-1|OwnerPartId=-1|Location.X=540|Location.Y=270|Color=128
|RECORD=29|IndexInSheet=-1|OwnerPartId=-1|Location.X=720|Location.Y=820|Color=128
|RECORD=29|IndexInSheet=-1|OwnerPartId=-1|Location.X=730|Location.Y=830|Color=128
|RECORD=29|IndexInSheet=-1|OwnerPartId=-1|Location.X=740|Location.Y=840|Color=128
|RECORD=29|IndexInSheet=-1|OwnerPartId=-1|Location.X=748|Location.Y=957|Color=128
|RECORD=29|IndexInSheet=-1|OwnerPartId=-1|Location.X=750|Location.Y=850|Color=128
|RECORD=29|IndexInSheet=-1|OwnerPartId=-1|Location.X=970|Location.Y=550|Color=128
|RECORD=29|IndexInSheet=-1|OwnerPartId=-1|Location.X=970|Location.Y=560|Color=128
|RECORD=29|IndexInSheet=-1|OwnerPartId=-1|Location.X=980|Location.Y=740|Color=128
|RECORD=29|IndexInSheet=-1|OwnerPartId=-1|Location.X=980|Location.Y=750|Color=128
|RECORD=29|IndexInSheet=-1|OwnerPartId=-1|Location.X=990|Location.Y=260|Color=128
|RECORD=29|IndexInSheet=-1|OwnerPartId=-1|Location.X=1010|Location.Y=290|Color=128
|RECORD=29|IndexInSheet=-1|OwnerPartId=-1|Location.X=1010|Location.Y=850|Color=128
|RECORD=29|IndexInSheet=-1|OwnerPartId=-1|Location.X=1020|Location.Y=840|Color=128
|RECORD=29|IndexInSheet=-1|OwnerPartId=-1|Location.X=1030|Location.Y=830|Color=128
|RECORD=29|IndexInSheet=-1|OwnerPartId=-1|Location.X=1040|Location.Y=260|Color=128
|RECORD=29|IndexInSheet=-1|OwnerPartId=-1|Location.X=1060|Location.Y=810|Color=128
|RECORD=29|IndexInSheet=-1|OwnerPartId=-1|Location.X=1070|Location.Y=800|Color=128
|RECORD=29|IndexInSheet=-1|OwnerPartId=-1|Location.X=1080|Location.Y=230|Color=128
|RECORD=29|IndexInSheet=-1|OwnerPartId=-1|Location.X=1090|Location.Y=780|Color=128
|RECORD=29|IndexInSheet=-1|OwnerPartId=-1|Location.X=1281|Location.Y=950|Color=128
|RECORD=29|IndexInSheet=-1|OwnerPartId=-1|Location.X=1340|Location.Y=906|Color=128
|RECORD=29|IndexInSheet=-1|OwnerPartId=-1|Location.X=1340|Location.Y=950|Color=128
|RECORD=29|IndexInSheet=-1|OwnerPartId=-1|Location.X=1390|Location.Y=950|Color=128